P  JOB   DA0T6MTH8C0_t6m_tray_bp_c_brd_103112_274.brd
P  UNITS CUST 
P  DIM   N
C  
C  Nov 26 11:27:16 2013
C  
C  IPC-D-356 Netlist From Allegro
C  
317GND              H7    -9    D0220PA00X+000822Y+002800               S0      
317GND              H7    -3    D0220PA00X+000822Y+000901               S0      
317GND              H7    -2    D0220PA00X+000429Y+001850               S0      
317N39398095        JP8   -2    D0460PA00X+000909Y+008016               S0      
317N39391900        JP4   -2    D0460PA00X+000909Y+009196               S0      
317GND              H7    -4    D0220PA00X+001772Y+000507               S0      
317N/C              H7    -1    D1420UA00X+001772Y+001850               S0      
317GND              H7    -7    D0220PA00X+002721Y+002800               S0      
317GND              H7    -6    D0220PA00X+003115Y+001850               S0      
317GND              H7    -5    D0220PA00X+002721Y+000901               S0      
317GND              H7    -8    D0220PA00X+001772Y+003193               S0      
317NODE3_EN         JP8   -1    D0460PA00X+001909Y+008016               S0      
317NODE1_EN         JP4   -1    D0460PA00X+001909Y+009196               S0      
317N/C              H5    -1    D1380UA00X+001772Y+011417               S0      
327NODE4_RXD        J19   -S7         A08X+000874Y+019410X0320Y1970R180 S1      
327NODE4_TXD        J19   -S8         A08X+001374Y+019410X0320Y1970R180 S1      
327NODE4_EN         J19   -S9         A08X+001874Y+019410X0320Y1970R180 S1      
327NODE3_EN         J19   -S10        A08X+002374Y+019410X0320Y1970R180 S1      
327NODE3_RXD        J19   -S11        A08X+002874Y+019410X0320Y1970R180 S1      
327NODE2_RXD        J19   -S6         A01X+000874Y+019410X0320Y1970R180 S2      
327NODE2_TXD        J19   -S5         A01X+001374Y+019410X0320Y1970R180 S2      
327NODE2_EN         J19   -S4         A01X+001874Y+019410X0320Y1970R180 S2      
327NODE1_EN         J19   -S3         A01X+002374Y+019410X0320Y1970R180 S2      
327NODE1_RXD        J19   -S2         A01X+002874Y+019410X0320Y1970R180 S2      
317N/C              J20   -H2   D0430UA00X+004083Y+002953               S0      
317P12V             J20   -18   D0430PA00X+004453Y+004134               S0      
317P12V             J20   -17   D0430PA00X+004453Y+005315               S0      
317GND              J20   -9    D0430PA00X+005634Y+004134               S0      
317GND              J20   -8    D0430PA00X+005634Y+005315               S0      
317P12V             J20   -16   D0430PA00X+004453Y+006496               S0      
317P12V             J20   -15   D0430PA00X+004453Y+007677               S0      
317GND              J20   -7    D0430PA00X+005634Y+006496               S0      
317GND              J20   -6    D0430PA00X+005634Y+007677               S0      
317P12V             J20   -14   D0430PA00X+004453Y+008858               S0      
317P12V             J20   -13   D0430PA00X+004453Y+010039               S0      
317GND              J20   -5    D0430PA00X+005634Y+008858               S0      
317GND              J20   -4    D0430PA00X+005634Y+010039               S0      
317P12V             J20   -12   D0430PA00X+004453Y+011221               S0      
317P12V             J20   -11   D0430PA00X+004453Y+012402               S0      
317GND              J20   -3    D0430PA00X+005634Y+011221               S0      
317GND              J20   -2    D0430PA00X+005634Y+012402               S0      
317N/C              J20   -H1   D0430UA00X+004083Y+014764               S0      
31710               J20   -10   D0430PA00X+004453Y+013583               S0      
317GND              J20   -1    D0430PA00X+005634Y+013583               S0      
317P12V             VIA   -     D0200PA00X+005190Y+016230               S3      
317P12V             VIA   -     D0200PA00X+005320Y+016950               S3      
327NODE3_TXD        J19   -S12        A08X+003374Y+019410X0320Y1970R180 S1      
327P12V             J19   -P5         A08X+006252Y+019154X2480Y3730R090 S1      
327NODE1_TXD        J19   -S1         A01X+003374Y+019410X0320Y1970R180 S2      
327P12V             J19   -P4         A01X+006252Y+019154X2480Y3730R090 S2      
317P12V             VIA   -     D0200PA00X+007690Y+002020               S3      
32710               VIA   -           A08X+006840Y+014120X0260Y0260     S1      
317P12V             VIA   -     D0200PA00X+006560Y+016040               S3      
317P12V             VIA   -     D0200PA00X+005720Y+016530               S3      
317P12V             VIA   -     D0200PA00X+007320Y+016210               S3      
317P12V             VIA   -     D0200PA00X+006220Y+016990               S3      
317P12V             VIA   -     D0100PA00X+006450Y+016520               S1      
317P12V             VIA   -     D0200PA00X+007040Y+017000               S3      
317P12V             VIA   -     D0200PA00X+009020Y+002240               S3      
317N/C              J21   -H2   D0420UA00X+008587Y+007284               S0      
317N/C              J21   -4    D0380PA00X+008193Y+007677               S0      
317N/C              J21   -2    D0380PA00X+008193Y+006890               S0      
317N/C              J21   -3    D0380PA00X+008980Y+007677               S0      
317PS_EN_PSU_N      J21   -1    D0380PA00X+008980Y+006890               S0      
317N/C              J21   -10   D0380PA00X+008193Y+010039               S0      
317N/C              J21   -8    D0380PA00X+008193Y+009252               S0      
317N/C              J21   -6    D0380PA00X+008193Y+008465               S0      
317N/C              J21   -9    D0380PA00X+008980Y+010039               S0      
317N/C              J21   -7    D0380PA00X+008980Y+009252               S0      
317N/C              J21   -5    D0380PA00X+008980Y+008465               S0      
317N/C              J21   -H1   D0420UA00X+008587Y+010433               S0      
317N/C              J21   -12   D0380PA00X+008193Y+010827               S0      
317GND              J21   -11   D0380PA00X+008980Y+010827               S0      
317NODE1_TXD        VIA   -     D0100PA00X+009910Y+012747               S1      
317P12V             VIA   -     D0200PA00X+009490Y+014450               S3      
317P12V             VIA   -     D0200PA00X+008380Y+015450               S3      
317P12V             VIA   -     D0200PA00X+009900Y+014890               S3      
317P12V             VIA   -     D0200PA00X+007880Y+015800               S3      
317P12V             VIA   -     D0200PA00X+009390Y+016290               S3      
317P12V             VIA   -     D0200PA00X+009020Y+016950               S3      
317P12V             VIA   -     D0200PA00X+008160Y+016260               S3      
317P12V             VIA   -     D0200PA00X+009260Y+015480               S3      
317P12V             VIA   -     D0200PA00X+010070Y+016340               S3      
317P12V             VIA   -     D0200PA00X+008900Y+015020               S3      
317P12V             VIA   -     D0200PA00X+008800Y+015890               S3      
317P12V             VIA   -     D0200PA00X+008350Y+016970               S3      
317P12V             VIA   -     D0200PA00X+007820Y+016990               S3      
317P12V             VIA   -     D0200PA00X+009690Y+016950               S3      
317P12V             VIA   -     D0200PA00X+009800Y+015710               S3      
317P12V             VIA   -     D0100PA00X+008940Y+016530               S1      
327P12V             J19   -P6         A08X+010252Y+019154X2480Y3730R090 S1      
327P12V             J19   -P3         A01X+010252Y+019154X2480Y3730R090 S2      
317P12V             VIA   -     D0200PA00X+010250Y+002940               S3      
317P12V             VIA   -     D0200PA00X+010720Y+001930               S3      
327N/C                    -           A01X+010940Y+004100X0400Y0400     S2      
327N/C                    -           A08X+010950Y+004100X0400Y0400     S1      
317P12V             VIA   -     D0200PA00X+012120Y+003390               S3      
317GND              VIA   -     D0200PA00X+012310Y+004960               S3      
327PS_EN_PSU_N      R33   -2          A01X+010174Y+006596X0180Y0200R270 S2      
327GND              R33   -1          A01X+010174Y+006281X0180Y0200R270 S2      
327GND              R85   -2          A01X+011196Y+006293X0180Y0200R090 S2      
327N39386877        R85   -1          A01X+011196Y+006608X0180Y0200R090 S2      
327GND              R87   -2          A01X+012196Y+006293X0180Y0200R090 S2      
327N39391900        R87   -1          A01X+012196Y+006608X0180Y0200R090 S2      
327GND              R89   -2          A01X+011696Y+006293X0180Y0200R090 S2      
327N39395053        R89   -1          A01X+011696Y+006608X0180Y0200R090 S2      
327GND              R91   -2          A01X+010696Y+006293X0180Y0200R090 S2      
327N39398095        R91   -1          A01X+010696Y+006608X0180Y0200R090 S2      
327N39386877        R84   -1          A01X+011196Y+007613X0180Y0200R270 S2      
327N39391900        R86   -1          A01X+012196Y+007613X0180Y0200R270 S2      
327N39395053        R88   -1          A01X+011696Y+007613X0180Y0200R270 S2      
327N39398095        R90   -1          A01X+010696Y+007613X0180Y0200R270 S2      
317GND              VIA   -     D0100PA00X+012050Y+005940               S3      
317GND              VIA   -     D0100PA00X+011440Y+005970               S3      
317GND              VIA   -     D0100PA00X+010750Y+005950               S3      
317GND              VIA   -     D0100PA00X+010240Y+005960               S1      
317N39386877        VIA   -     D0100PA00X+011196Y+007360               S1      
317N39391900        VIA   -     D0100PA00X+012196Y+007090               S1      
317N39395053        VIA   -     D0100PA00X+011696Y+006860               S1      
317N39398095        VIA   -     D0100PA00X+010696Y+006850               S1      
327P12V             R84   -2          A01X+011196Y+007928X0180Y0200R270 S2      
327P12V             R86   -2          A01X+012196Y+007928X0180Y0200R270 S2      
327P12V             R88   -2          A01X+011696Y+007928X0180Y0200R270 S2      
327P12V             R90   -2          A01X+010696Y+007928X0180Y0200R270 S2      
317N39395053        JP7   -2    D0460PA00X+010929Y+009246               S0      
317NODE4_EN         JP7   -1    D0460PA00X+011929Y+009246               S0      
317P12V             VIA   -     D0100PA00X+012276Y+008244               S3      
317P12V             VIA   -     D0100PA00X+011716Y+008254               S3      
317P12V             VIA   -     D0100PA00X+011216Y+008234               S3      
317P12V             VIA   -     D0100PA00X+010696Y+008214               S3      
317N39386877        JP3   -2    D0460PA00X+010929Y+010396               S0      
317NODE2_EN         JP3   -1    D0460PA00X+011929Y+010396               S0      
317NODE2_RXD        VIA   -     D0100PA00X+010259Y+011568               S1      
317NODE1_EN         VIA   -     D0100PA00X+011540Y+012027               S1      
317NODE1_RXD        VIA   -     D0100PA00X+010739Y+012511               S1      
317NODE4_RXD        VIA   -     D0100PA00X+011980Y+012439               S1      
317NODE3_TXD        VIA   -     D0100PA00X+010890Y+013730               S1      
317NODE3_RXD        VIA   -     D0100PA00X+011430Y+013490               S1      
317P12V             VIA   -     D0200PA00X+010200Y+014190               S3      
317P12V             VIA   -     D0200PA00X+011400Y+014520               S3      
317P12V             VIA   -     D0200PA00X+011990Y+014320               S3      
317P12V             VIA   -     D0200PA00X+010860Y+014310               S3      
317NODE3_EN         VIA   -     D0100PA00X+011970Y+013240               S1      
317NODE4_EN         VIA   -     D0100PA00X+011150Y+012990               S1      
317P12V             VIA   -     D0200PA00X+011180Y+015180               S3      
317P12V             VIA   -     D0200PA00X+010490Y+015740               S3      
317P12V             VIA   -     D0200PA00X+012050Y+015720               S3      
317P12V             VIA   -     D0200PA00X+011190Y+016480               S3      
317P12V             VIA   -     D0200PA00X+011810Y+016210               S3      
317P12V             VIA   -     D0200PA00X+010450Y+015030               S3      
317P12V             VIA   -     D0200PA00X+011090Y+015920               S3      
317P12V             VIA   -     D0200PA00X+011840Y+015200               S3      
317P12V             VIA   -     D0100PA00X+010580Y+016540               S1      
317P12V             VIA   -     D0200PA00X+010650Y+017030               S3      
317P12V             VIA   -     D0200PA00X+011530Y+017020               S3      
317GND              VIA   -     D0200PA00X+014330Y+002730               S3      
317P12V             VIA   -     D0200PA00X+012390Y+004100               S3      
317GND              VIA   -     D0200PA00X+014380Y+005360               S3      
317GND              VIA   -     D0200PA00X+014450Y+004000               S3      
317P12V             VIA   -     D0200PA00X+013870Y+006350               S3      
317P12V             VIA   -     D0200PA00X+014410Y+007290               S3      
317GND              VIA   -     D0200PA00X+013310Y+007130               S3      
317P12V             VIA   -     D0200PA00X+013980Y+009020               S3      
317P12V             VIA   -     D0200PA00X+013140Y+009130               S3      
317P12V             VIA   -     D0100PA00X+012556Y+007964               S3      
317GND              VIA   -     D0200PA00X+014420Y+009630               S3      
317NODE2_TXD        VIA   -     D0100PA00X+012860Y+011451               S1      
317P12V             VIA   -     D0200PA00X+012920Y+010130               S3      
317GND              VIA   -     D0200PA00X+014300Y+010570               S3      
317NODE2_EN         VIA   -     D0100PA00X+013250Y+011010               S1      
317NODE4_TXD        VIA   -     D0100PA00X+012500Y+012640               S1      
317P12V             VIA   -     D0200PA00X+012920Y+014240               S3      
317P12V             VIA   -     D0200PA00X+012660Y+014950               S3      
317GND              VIA   -     D0200PA00X+014190Y+015470               S3      
317GND              VIA   -     D0200PA00X+013480Y+016400               S3      
317GND              VIA   -     D0200PA00X+014470Y+014920               S3      
317GND              VIA   -     D0200PA00X+013710Y+015860               S3      
317GND              VIA   -     D0100PA00X+014140Y+016480               S1      
317GND              VIA   -     D0100PA00X+012900Y+016480               S1      
327GND              J19   -P7         A08X+014252Y+019154X2480Y3730R090 S1      
327GND              J19   -P2         A01X+014252Y+019154X2480Y3730R090 S2      
317GND              VIA   -     D0200PA00X+013700Y+017040               S3      
317GND              VIA   -     D0200PA00X+012740Y+017040               S3      
317P12V             VIA   -     D0200PA00X+016560Y+001940               S3      
317GND              VIA   -     D0200PA00X+015030Y+002020               S3      
317P12V             VIA   -     D0200PA00X+016810Y+004840               S3      
317P12V             VIA   -     D0200PA00X+015150Y+003580               S3      
317GND              VIA   -     D0200PA00X+016650Y+003470               S3      
317GND              VIA   -     D0200PA00X+015310Y+004960               S3      
317P12V             VIA   -     D0200PA00X+015980Y+006510               S3      
317P12V             VIA   -     D0200PA00X+016180Y+008680               S3      
317GND              VIA   -     D0200PA00X+014880Y+008500               S3      
317P12V             VIA   -     D0200PA00X+015820Y+010240               S3      
317GND              VIA   -     D0200PA00X+016350Y+014490               S3      
317GND              VIA   -     D0200PA00X+015030Y+014460               S3      
317GND              VIA   -     D0200PA00X+015600Y+013820               S3      
317GND              VIA   -     D0200PA00X+015650Y+014480               S3      
317GND              VIA   -     D0200PA00X+016990Y+014680               S3      
317GND              VIA   -     D0200PA00X+016440Y+013820               S3      
317GND              VIA   -     D0200PA00X+016940Y+015360               S3      
317GND              VIA   -     D0200PA00X+015560Y+015790               S3      
317GND              VIA   -     D0200PA00X+016210Y+016430               S3      
317GND              VIA   -     D0200PA00X+016800Y+016120               S3      
317GND              VIA   -     D0200PA00X+014930Y+016410               S3      
317GND              VIA   -     D0200PA00X+016320Y+015160               S3      
317GND              VIA   -     D0200PA00X+016200Y+015940               S3      
317GND              VIA   -     D0200PA00X+014800Y+015880               S3      
317GND              VIA   -     D0200PA00X+015260Y+015200               S3      
317GND              VIA   -     D0100PA00X+016920Y+016520               S1      
317GND              VIA   -     D0100PA00X+015550Y+016480               S1      
327GND              J19   -P8         A08X+018252Y+019154X2480Y3730R090 S1      
327GND              J19   -P1         A01X+018252Y+019154X2480Y3730R090 S2      
317GND              VIA   -     D0200PA00X+015590Y+017000               S3      
317GND              VIA   -     D0200PA00X+016380Y+017010               S3      
317GND              VIA   -     D0200PA00X+014860Y+017010               S3      
317GND              VIA   -     D0200PA00X+018030Y+002020               S3      
317P12V             VIA   -     D0200PA00X+018410Y+003660               S3      
317GND              VIA   -     D0200PA00X+018310Y+004960               S3      
317P12V             VIA   -     D0200PA00X+017430Y+007330               S3      
317GND              VIA   -     D0200PA00X+019170Y+007540               S3      
317GND              VIA   -     D0200PA00X+017500Y+006230               S3      
317P12V             VIA   -     D0200PA00X+018140Y+008470               S3      
317GND              VIA   -     D0200PA00X+017420Y+009630               S3      
317GND              VIA   -     D0200PA00X+019040Y+013660               S3      
317GND              VIA   -     D0200PA00X+019120Y+014240               S3      
317GND              VIA   -     D0200PA00X+017810Y+014460               S3      
317GND              VIA   -     D0200PA00X+018400Y+013880               S3      
317GND              VIA   -     D0200PA00X+017360Y+013870               S3      
317GND              VIA   -     D0200PA00X+018580Y+014540               S3      
317GND              VIA   -     D0200PA00X+019000Y+014980               S3      
317GND              VIA   -     D0200PA00X+017930Y+015640               S3      
317GND              VIA   -     D0200PA00X+018710Y+015580               S3      
317GND              VIA   -     D0200PA00X+019210Y+016350               S3      
317GND              VIA   -     D0200PA00X+017630Y+016440               S3      
317GND              VIA   -     D0200PA00X+017550Y+015130               S3      
317GND              VIA   -     D0200PA00X+017370Y+015870               S3      
317GND              VIA   -     D0200PA00X+019040Y+016980               S3      
317GND              VIA   -     D0200PA00X+018260Y+015200               S3      
317GND              VIA   -     D0100PA00X+018330Y+016470               S1      
317GND              VIA   -     D0200PA00X+017130Y+017000               S3      
317GND              VIA   -     D0200PA00X+017780Y+017040               S3      
317P12V             VIA   -     D0200PA00X+019440Y+002020               S3      
317P12V             VIA   -     D0200PA00X+019780Y+003090               S3      
317GND              VIA   -     D0200PA00X+021030Y+002020               S3      
317P12V             VIA   -     D0200PA00X+019780Y+004800               S3      
317P12V             VIA   -     D0200PA00X+021470Y+003580               S3      
317GND              VIA   -     D0200PA00X+021310Y+004960               S3      
317P12V             VIA   -     D0200PA00X+019560Y+006410               S3      
317P12V             VIA   -     D0200PA00X+020670Y+007270               S3      
317GND              VIA   -     D0200PA00X+020940Y+006090               S3      
317GND              VIA   -     D0200PA00X+020420Y+009630               S3      
317GND              VIA   -     D0200PA00X+019620Y+010230               S3      
317GND              VIA   -     D0200PA00X+021130Y+013860               S3      
317GND              VIA   -     D0200PA00X+020420Y+013920               S3      
317GND              VIA   -     D0200PA00X+019590Y+014630               S3      
317GND              VIA   -     D0200PA00X+021330Y+014680               S3      
317GND              VIA   -     D0200PA00X+019730Y+013910               S3      
317GND              VIA   -     D0200PA00X+020510Y+014770               S3      
317GND              VIA   -     D0200PA00X+020150Y+015440               S3      
317GND              VIA   -     D0200PA00X+021350Y+015540               S3      
317GND              VIA   -     D0200PA00X+019710Y+016080               S3      
317GND              VIA   -     D0200PA00X+019460Y+015480               S3      
317P12V             VIA   -     D0200PA00X+022580Y+001960               S3      
317P12V             VIA   -     D0200PA00X+022920Y+003090               S3      
317GND              VIA   -     D0200PA00X+022710Y+004300               S3      
317P12V             VIA   -     D0200PA00X+021640Y+010050               S3      
317GND              VIA   -     D0200PA00X+023420Y+009630               S3      
317GND              VIA   -     D0200PA00X+022560Y+010450               S3      
317GND              VIA   -     D0200PA00X+023450Y+013870               S3      
317GND              VIA   -     D0200PA00X+023060Y+014640               S3      
317GND              VIA   -     D0200PA00X+021810Y+014050               S3      
317GND              VIA   -     D0200PA00X+022440Y+013820               S3      
317GND              VIA   -     D0200PA00X+023680Y+016500               S3      
317GND              VIA   -     D0200PA00X+023880Y+015750               S3      
317GND              VIA   -     D0200PA00X+023160Y+015510               S3      
317GND              VIA   -     D0200PA00X+022180Y+014940               S3      
317GND              VIA   -     D0200PA00X+023650Y+018590               S3      
317GND              VIA   -     D0200PA00X+023540Y+017290               S3      
317P12V             VIA   -     D0200PA00X+025440Y+001920               S3      
317GND              VIA   -     D0200PA00X+024030Y+002020               S3      
317P12V             VIA   -     D0200PA00X+025780Y+005120               S3      
317P12V             VIA   -     D0200PA00X+024490Y+003660               S3      
317GND              VIA   -     D0200PA00X+024310Y+004960               S3      
317P12V             VIA   -     D0200PA00X+025440Y+007430               S3      
317P12V             VIA   -     D0200PA00X+025160Y+010010               S3      
317GND              VIA   -     D0200PA00X+024860Y+014290               S3      
317GND              VIA   -     D0200PA00X+024260Y+014010               S3      
317GND              VIA   -     D0200PA00X+025440Y+013820               S3      
317P12V             VIA   -     D0200PA00X+025220Y+015940               S3      
317GND              VIA   -     D0200PA00X+023960Y+014870               S3      
317GND              VIA   -     D0200PA00X+024510Y+016520               S3      
317GND              VIA   -     D0200PA00X+025540Y+014840               S3      
317GND              VIA   -     D0200PA00X+024560Y+015700               S3      
317GND              VIA   -     D0200PA00X+024840Y+014980               S3      
317P12V             VIA   -     D0200PA00X+025280Y+017990               S3      
317GND              VIA   -     D0200PA00X+023980Y+017870               S3      
317GND              VIA   -     D0200PA00X+024330Y+018560               S3      
317GND              VIA   -     D0200PA00X+024230Y+017180               S3      
317GND              VIA   -     D0200PA00X+025260Y+019200               S3      
317GND              VIA   -     D0200PA00X+024240Y+019330               S3      
317GND              VIA   -     D0200PA00X+027030Y+002020               S3      
317P12V             VIA   -     D0200PA00X+026830Y+003620               S3      
317GND              VIA   -     D0200PA00X+027310Y+004960               S3      
317P12V             VIA   -     D0200PA00X+028360Y+006950               S3      
317P12V             VIA   -     D0200PA00X+027330Y+009490               S3      
317GND              VIA   -     D0200PA00X+026420Y+009630               S3      
317P12V             VIA   -     D0200PA00X+028180Y+010090               S3      
317GND              VIA   -     D0200PA00X+026290Y+010490               S3      
317P12V             VIA   -     D0200PA00X+026770Y+014520               S3      
317GND              VIA   -     D0200PA00X+028440Y+013820               S3      
317P12V             VIA   -     D0200PA00X+028000Y+015980               S3      
317P12V             VIA   -     D0200PA00X+028100Y+018070               S3      
317GND              VIA   -     D0200PA00X+026530Y+017000               S3      
317GND              VIA   -     D0200PA00X+028260Y+019200               S3      
317GND              J11   -2    D1580PA00X+030677Y+001969               S0      
317GND              J11   -1    D1580PA00X+030677Y+004185               S0      
317GND              J11   -3    D1580PA00X+030677Y+006791               S0      
317GND              VIA   -     D0200PA00X+029420Y+009630               S3      
317P12V             VIA   -     D0200PA00X+030780Y+010110               S3      
317P12V             VIA   -     D0200PA00X+030030Y+014000               S3      
317N/C              H3    -1    D1380UA00X+031421Y+016339               S0      
317GND              VIA   -     D0200PA00X+028760Y+015000               S3      
317GND              VIA   -     D0200PA00X+029280Y+016980               S3      
317GND              VIA   -     D0200PA00X+032420Y+009630               S3      
317GND              VIA   -     D0200PA00X+031460Y+010410               S3      
327NNAME10000       L2    -2          A01X+033200Y+012896X0440Y0540R090 S2      
327NNAME10001       L2    -1          A01X+033200Y+013644X0440Y0540R090 S2      
317GND              VIA   -     D0200PA00X+031020Y+013590               S3      
317GND              J3    -D6   D0300PA00X+034378Y+001181               S0      
317GND              J3    -D5   D0300PA00X+034378Y+001968               S0      
317GND              J3    -D4   D0300PA00X+034378Y+002756               S0      
317GND              J3    -D3   D0300PA00X+033591Y+001181               S0      
317GND              J3    -D2   D0300PA00X+033591Y+001968               S0      
317GND              J3    -D1   D0300PA00X+033591Y+002756               S0      
317GND              J3    -A6   D0300PA00X+034378Y+004331               S0      
317GND              J3    -A5   D0300PA00X+034378Y+005118               S0      
317GND              J3    -A3   D0300PA00X+033591Y+004331               S0      
317GND              J3    -A2   D0300PA00X+033591Y+005118               S0      
317N/C              J3    -H1   D0850UA00X+035165Y+003740               S0      
317GND              J3    -A4   D0300PA00X+034378Y+005905               S0      
317GND              J3    -A1   D0300PA00X+033591Y+005905               S0      
327P12V             C2    -1          A01X+034652Y+009010X0280Y0320     S2      
327GND              C2    -2          A01X+034652Y+009590X0280Y0320     S2      
327P12V             C1    -1          A01X+035242Y+009010X0280Y0320     S2      
327GND              C1    -2          A01X+035242Y+009590X0280Y0320     S2      
327GND              R44   -1          A01X+035047Y+010856X0180Y0200R180 S2      
327GND              R45   -1          A01X+035047Y+010296X0180Y0200R180 S2      
327GND              R47   -1          A01X+035047Y+011466X0180Y0200R180 S2      
327NNAME10000       R78   -2          A01X+035446Y+012164X0440Y0540     S2      
317GND              VIA   -     D0100PA00X+034680Y+011350               S1      
317GND              VIA   -     D0100PA00X+034540Y+010760               S1      
317GND              VIA   -     D0100PA00X+034620Y+010250               S1      
317NNAME10000       VIA   -     D0100PA00X+035070Y+012164               S1      
327NNAME10002       FS4   -2          A01X+035209Y+013928X0400Y0710R180 S2      
327NNAME10003       L4    -2          A01X+034047Y+012906X0440Y0540R090 S2      
327NNAME10002       L4    -1          A01X+034047Y+013654X0440Y0540R090 S2      
327NNAME10003       R79   -2          A01X+035446Y+013014X0440Y0540     S2      
317NNAME10003       VIA   -     D0100PA00X+034590Y+012510               S1      
317NNAME10001       VIA   -     D0100PA00X+034735Y+014375               S1      
317NNAME10002       VIA   -     D0100PA00X+034691Y+013769               S1      
327NNAME10001       FS2   -2          A01X+035199Y+014912X0400Y0710R180 S2      
317P12V             VIA   -     D0200PA00X+035000Y+016180               S3      
317GND              VIA   -     D0200PA00X+033830Y+016290               S3      
317P12V             VIA   -     D0200PA00X+035020Y+018110               S3      
317GND              VIA   -     D0200PA00X+033830Y+018380               S3      
317P12V             J3    -C3   D0300PA00X+036740Y+001181               S0      
317P12V             J3    -C2   D0300PA00X+036740Y+001968               S0      
317P12V             J3    -C1   D0300PA00X+036740Y+002756               S0      
317P12V             J3    -C6   D0300PA00X+035953Y+001181               S0      
317P12V             J3    -C5   D0300PA00X+035953Y+001968               S0      
317P12V             J3    -C4   D0300PA00X+035953Y+002756               S0      
317P12V             J3    -B3   D0300PA00X+036740Y+004331               S0      
317P12V             J3    -B2   D0300PA00X+036740Y+005118               S0      
317P12V             J3    -B6   D0300PA00X+035953Y+004331               S0      
317P12V             J3    -B5   D0300PA00X+035953Y+005118               S0      
317P12V             J3    -B1   D0300PA00X+036740Y+005905               S0      
317P12V             J3    -B4   D0300PA00X+035953Y+005905               S0      
327GND              C3    -2          A01X+035826Y+009387X0180Y0200R270 S2      
327P12V             C3    -1          A01X+035826Y+009072X0180Y0200R270 S2      
327GND              C4    -2          A01X+036276Y+009387X0180Y0200R270 S2      
327P12V             C4    -1          A01X+036276Y+009072X0180Y0200R270 S2      
317GND              VIA   -     D0100PA00X+036250Y+009710               S1      
317GND              VIA   -     D0100PA00X+035760Y+009700               S3      
327ENET10G_2_RS1    R16   -2          A01X+036129Y+010296X0180Y0200     S2      
327P3V3_BLAD1       R16   -1          A01X+036444Y+010296X0180Y0200     S2      
327NNAME10004       R4    -2          A01X+036129Y+011466X0180Y0200     S2      
327P3V3_BLAD1       R4    -1          A01X+036444Y+011466X0180Y0200     S2      
327ENET10G_2_RS0    R12   -2          A01X+036129Y+010856X0180Y0200     S2      
327P3V3_BLAD1       R12   -1          A01X+036444Y+010856X0180Y0200     S2      
327ENET10G_2_RS0    R44   -2          A01X+035362Y+010856X0180Y0200R180 S2      
327ENET10G_2_RS1    R45   -2          A01X+035362Y+010296X0180Y0200R180 S2      
327NNAME10004       R47   -2          A01X+035362Y+011466X0180Y0200R180 S2      
327P3V3_BLAD1       R78   -1          A01X+036194Y+012164X0440Y0540     S2      
317NNAME10004       VIA   -     D0100PA00X+035780Y+011466               S1      
317ENET10G_2_RS0    VIA   -     D0100PA00X+035760Y+010856               S1      
317ENET10G_2_RS1    VIA   -     D0100PA00X+035686Y+010296               S1      
327P3V3_BLAD1       FS4   -1          A01X+036351Y+013928X0400Y0710R180 S2      
327P3V3_BLAD1       R79   -1          A01X+036194Y+013014X0440Y0540     S2      
317P3V3_BLAD1       VIA   -     D0100PA00X+036720Y+012400               S3      
327P3V3_BLAD1       FS2   -1          A01X+036341Y+014912X0400Y0710R180 S2      
317GND              VIA   -     D0200PA00X+035920Y+016490               S3      
317GND              VIA   -     D0200PA00X+035910Y+018440               S3      
317GND              J15   -16   D0370PA00X+039278Y+003226               S0      
317GND              VIA   -     D0100PA00X+039780Y+002360               S3      
317GND              VIA   -     D0100PA00X+039780Y+001950               S3      
327GND              U6    -11         A01X+039831Y+004051X0200Y0800R180 S2      
317N/C              U6    -21   D0630UA00X+039280Y+005665               S0      
317GND              J15   -19   D0370PA00X+038364Y+005038               S0      
317GND              J15   -10   D0410PA00X+038364Y+004053               S0      
317GND              VIA   -     D0100PA00X+039831Y+003500               S3      
317GND              VIA   -     D0100PA00X+039831Y+004610               S3      
327GND              U6    -10         A01X+039673Y+007280X0200Y0800R180 S2      
317GND              J15   -18   D0370PA00X+038364Y+007006               S0      
317GND              J15   -9    D0410PA00X+038364Y+007990               S0      
317GND              J15   -8    D0410PA00X+039612Y+009959               S0      
317GND              J15   -17   D0370PA00X+038364Y+008856               S0      
317GND              VIA   -     D0100PA00X+039673Y+007893               S3      
317GND              J15   -5    D0410PA00X+038364Y+011927               S0      
317GND              J15   -4    D0410PA00X+038364Y+015864               S0      
317GND              VIA   -     D0100PA00X+041790Y+000670               S3      
317GND              VIA   -     D0100PA00X+041490Y+000650               S1      
317GND              VIA   -     D0100PA00X+041020Y+000670               S3      
317GND              VIA   -     D0100PA00X+040440Y+000680               S3      
317GND              J15   -15   D0370PA00X+041167Y+003226               S0      
327GND              C24   -2          A01X+040360Y+000993X0180Y0200R090 S2      
327NNAME10003       C24   -1          A01X+040360Y+001308X0180Y0200R090 S2      
327GND              C23   -2          A01X+040820Y+000993X0180Y0200R090 S2      
327NNAME10003       C23   -1          A01X+040820Y+001308X0180Y0200R090 S2      
327GND              C19   -2          A01X+041280Y+001003X0180Y0200R090 S2      
327NNAME10000       C19   -1          A01X+041280Y+001318X0180Y0200R090 S2      
327GND              C20   -2          A01X+041720Y+001003X0180Y0200R090 S2      
327NNAME10000       C20   -1          A01X+041720Y+001318X0180Y0200R090 S2      
317GND              VIA   -     D0100PA00X+040820Y+002350               S3      
317GND              VIA   -     D0100PA00X+040820Y+001990               S3      
317ENET10G_2_RDP    VIA   -     D0100PA00X+040553Y+002196               S3      
317ENET10G_2_RDN    VIA   -     D0100PA00X+040053Y+002196               S3      
317NNAME10003       VIA   -     D0100PA00X+040010Y+001390               S3      
317NNAME10000       VIA   -     D0100PA00X+041280Y+001620               S3      
327GND              U6    -17         A01X+041721Y+004051X0200Y0800R180 S2      
327GND              U6    -14         A01X+040776Y+004051X0200Y0800R180 S2      
327NNAME10000       U6    -16         A01X+041406Y+004051X0200Y0800R180 S2      
327NNAME10003       U6    -15         A01X+041091Y+004051X0200Y0800R180 S2      
327ENET10G_2_TDP    U6    -18         A01X+042035Y+004051X0200Y0800R180 S2      
327ENET10G_2_RDN    U6    -12         A01X+040146Y+004051X0200Y0800R180 S2      
327ENET10G_2_RDP    U6    -13         A01X+040461Y+004051X0200Y0800R180 S2      
317GND              VIA   -     D0100PA00X+041721Y+003500               S3      
317GND              VIA   -     D0100PA00X+040760Y+003500               S3      
317GND              VIA   -     D0100PA00X+040776Y+004610               S3      
317GND              VIA   -     D0100PA00X+041721Y+004610               S3      
317NNAME10003       VIA   -     D0100PA00X+041091Y+004610               S3      
317NNAME10000       VIA   -     D0100PA00X+041406Y+004620               S3      
327NNAME10005       U6    -2          A01X+042193Y+007280X0200Y0800R180 S2      
327NNAME10004       U6    -3          A01X+041878Y+007280X0200Y0800R180 S2      
327ENET10G_2_RS1    U6    -9          A01X+039988Y+007280X0200Y0800R180 S2      
327ENET10G_2_RS0    U6    -7          A01X+040618Y+007280X0200Y0800R180 S2      
327ENET10G_2_SDA    U6    -4          A01X+041563Y+007280X0200Y0800R180 S2      
327ENET10G_2_SCL    U6    -5          A01X+041248Y+007280X0200Y0800R180 S2      
327NNAME10006       U6    -6          A01X+040933Y+007280X0200Y0800R180 S2      
327ENET10G_2_LOS    U6    -8          A01X+040303Y+007280X0200Y0800R180 S2      
317GND              J15   -7    D0410PA00X+041738Y+009959               S0      
317ENET10G_2_SCL    VIA   -     D0100PA00X+041248Y+008090               S3      
317ENET10G_2_LOS    VIA   -     D0100PA00X+040303Y+008953               S3      
317ENET10G_2_SDA    VIA   -     D0100PA00X+041563Y+008070               S3      
317NNAME10004       VIA   -     D0100PA00X+041230Y+008560               S3      
317NNAME10005       VIA   -     D0100PA00X+042193Y+007840               S3      
317NNAME10006       VIA   -     D0100PA00X+040933Y+008860               S3      
317ENET10G_2_RS0    VIA   -     D0100PA00X+040618Y+008230               S3      
317ENET10G_2_RS1    VIA   -     D0100PA00X+039988Y+007932               S3      
317GND              J15   -2    D0410PA00X+040596Y+017833               S0      
317GND              J15   -14   D0370PA00X+043057Y+003226               S0      
327GND              U6    -20         A01X+042665Y+004051X0200Y0800R180 S2      
327ENET10G_2_TDN    U6    -19         A01X+042350Y+004051X0200Y0800R180 S2      
317N/C              U6    -22   D0380UA00X+043059Y+005665               S0      
317GND              J15   -13   D0370PA00X+043974Y+005038               S0      
317GND              VIA   -     D0100PA00X+042650Y+003500               S3      
317GND              VIA   -     D0100PA00X+042665Y+004610               S3      
327GND              U6    -1          A01X+042508Y+007280X0200Y0800R180 S2      
317GND              J15   -20   D0330PA00X+043974Y+006022               S0      
317GND              J15   -12   D0370PA00X+043974Y+007006               S0      
317GND              J15   -6    D0410PA00X+043974Y+009959               S0      
317GND              J15   -11   D0370PA00X+043974Y+008856               S0      
317GND              VIA   -     D0100PA00X+042620Y+007810               S3      
317GND              J15   -3    D0410PA00X+043974Y+013896               S0      
317GND              J15   -1    D0410PA00X+043974Y+017833               S0      
317GND              J24   -A6   D0200PA00X+046665Y+000787               S0      
317ENET10G_2_RDP    J24   -E6   D0200PA00X+046665Y+002992               S0      
317GND              J24   -D6   D0200PA00X+046665Y+002441               S0      
317ENET1G_2_MDI3N   J24   -C6   D0200PA00X+046665Y+001890               S0      
317ENET1G_2_MDI3P   J24   -B6   D0200PA00X+046665Y+001339               S0      
317ENET10G_2_TDN    J24   -I6   D0200PA00X+046665Y+005197               S0      
317ENET10G_2_TDP    J24   -H6   D0200PA00X+046665Y+004646               S0      
317GND              J24   -G6   D0200PA00X+046665Y+004095               S0      
317ENET10G_2_RDN    J24   -F6   D0200PA00X+046665Y+003543               S0      
317GND              VIA   -     D0100PA00X+044600Y+003840               S3      
317GND              VIA   -     D0100PA00X+044600Y+003390               S3      
317GND              VIA   -     D0100PA00X+045540Y+003400               S3      
317GND              VIA   -     D0100PA00X+045540Y+003860               S3      
317ENET10G_2_TDN    VIA   -     D0100PA00X+044788Y+003620               S3      
317ENET10G_2_TDP    VIA   -     D0100PA00X+045348Y+003620               S3      
317GND              VIA   -     D0100PA00X+046560Y+005590               S3      
327NNAME10005       R2    -2          A01X+046029Y+008732X0180Y0200     S2      
327P3V3_BLAD1       R2    -1          A01X+046344Y+008732X0180Y0200     S2      
327ENET10G_2_SDA    R6    -2          A01X+046029Y+009162X0180Y0200     S2      
327P3V3_BLAD1       R6    -1          A01X+046344Y+009162X0180Y0200     S2      
327ENET10G_2_SCL    R8    -2          A01X+046029Y+009592X0180Y0200     S2      
327P3V3_BLAD1       R8    -1          A01X+046344Y+009592X0180Y0200     S2      
327NNAME10005       R46   -2          A01X+046029Y+008302X0180Y0200     S2      
327GND              R46   -1          A01X+046344Y+008302X0180Y0200     S2      
317GND              VIA   -     D0100PA00X+046344Y+007987               S1      
317ENET10G_2_SCL    VIA   -     D0100PA00X+045390Y+009230               S1      
317ENET10G_2_LOS    VIA   -     D0100PA00X+046620Y+008756               S3      
317ENET10G_2_SDA    VIA   -     D0100PA00X+045330Y+008680               S1      
317NNAME10005       VIA   -     D0100PA00X+045110Y+008140               S1      
317NNAME10006       VIA   -     D0100PA00X+045210Y+009700               S1      
317NNAME10006       VIA   -     D0100PA00X+046610Y+008326               S3      
327ENET10G_2_LOS    R14   -2          A01X+046029Y+010452X0180Y0200     S2      
327P3V3_BLAD1       R14   -1          A01X+046344Y+010452X0180Y0200     S2      
327NNAME10006       R10   -2          A01X+046029Y+010022X0180Y0200     S2      
327P3V3_BLAD1       R10   -1          A01X+046344Y+010022X0180Y0200     S2      
317ENET1G_2_MDI0P   J22   -B1   D0350PA00X+046886Y+011567               S0      
317ENET10G_2_LOS    VIA   -     D0100PA00X+045200Y+010220               S1      
317P3V3_BLAD1       VIA   -     D0100PA00X+046630Y+010090               S3      
317GND              J22   -G6   D0800PA00X+045288Y+013165               S0      
317ENET1G_1_MDI3N   J22   -A8   D0350PA00X+046886Y+014165               S0      
317GND              J22   -G5   D0800PA00X+045587Y+015366               S0      
317GND              J22   -G4   D0800PA00X+045288Y+019464               S0      
317N/C              J22   -H2   D1280UA00X+046386Y+017665               S0      
317ENET1G_2_MDI1P   J24   -A5   D0200PA00X+047453Y+000827               S0      
317GND              J24   -A4   D0200PA00X+048240Y+000787               S0      
317ENET1G_1_MDI3P   J24   -A3   D0200PA00X+049028Y+000827               S0      
317GND              VIA   -     D0100PA00X+047450Y+000390               S3      
317GND              VIA   -     D0100PA00X+049020Y+000400               S3      
317ENET1G_2_MDI2N   J24   -E5   D0200PA00X+047453Y+003032               S0      
317ENET10G_2_SDA    J24   -E4   D0200PA00X+048240Y+002992               S0      
317ENET10G_1_SCL    J24   -E3   D0200PA00X+049028Y+003032               S0      
317ENET1G_2_MDI2P   J24   -D5   D0200PA00X+047453Y+002480               S0      
317GND              J24   -D4   D0200PA00X+048240Y+002441               S0      
317ENET10G_1_SDA    J24   -D3   D0200PA00X+049028Y+002480               S0      
317GND              J24   -C5   D0200PA00X+047453Y+001929               S0      
317ENET1G_2_MDI0N   J24   -C4   D0200PA00X+048240Y+001890               S0      
317GND              J24   -C3   D0200PA00X+049028Y+001929               S0      
317ENET1G_2_MDI1N   J24   -B5   D0200PA00X+047453Y+001378               S0      
317ENET1G_2_MDI0P   J24   -B4   D0200PA00X+048240Y+001339               S0      
317ENET1G_1_MDI3N   J24   -B3   D0200PA00X+049028Y+001378               S0      
317BLADE1_MATED_N   J24   -I5   D0200PA00X+047453Y+005236               S0      
317NNAME10007       J24   -I4   D0200PA00X+048240Y+005197               S0      
317P3V3_BLAD1       J24   -I3   D0200PA00X+049028Y+005236               S0      
317SFP2_PRESENT_N   J24   -H5   D0200PA00X+047453Y+004685               S0      
317NODE2_TXD        J24   -H4   D0200PA00X+048240Y+004646               S0      
317NODE1_TXD        J24   -H3   D0200PA00X+049028Y+004685               S0      
317NODE2_EN         J24   -G5   D0200PA00X+047453Y+004134               S0      
317NODE2_RXD        J24   -G4   D0200PA00X+048240Y+004095               S0      
317NODE1_RXD        J24   -G3   D0200PA00X+049028Y+004134               S0      
317GND              J24   -F5   D0200PA00X+047453Y+003583               S0      
317ENET10G_2_SCL    J24   -F4   D0200PA00X+048240Y+003543               S0      
317NNAME10008       J24   -F3   D0200PA00X+049028Y+003583               S0      
317NODE1_TXD        VIA   -     D0100PA00X+048880Y+007370               S3      
327BLADE1_MATED_N   R34   -2          A01X+047763Y+008328X0180Y0200R090 S2      
327GND              R34   -1          A01X+047763Y+008643X0180Y0200R090 S2      
327P3V3_BLAD1       R57   -2          A01X+048326Y+008721X0180Y0200R270 S2      
327NNAME10007       R57   -1          A01X+048326Y+008406X0180Y0200R270 S2      
327SFP2_PRESENT_N   R59   -2          A01X+047469Y+009196X0180Y0200     S2      
327GND              R59   -1          A01X+047784Y+009196X0180Y0200     S2      
327NNAME10007       R56   -2          A01X+048756Y+008406X0180Y0200R090 S2      
327GND              R56   -1          A01X+048756Y+008721X0180Y0200R090 S2      
327SFP2_PRESENT_N   R68   -2          A01X+047179Y+008756X0180Y0200R180 S2      
327ENET10G_2_LOS    R68   -1          A01X+046864Y+008756X0180Y0200R180 S2      
327SFP2_PRESENT_N   R69   -2          A01X+047179Y+008326X0180Y0200R180 S2      
327NNAME10006       R69   -1          A01X+046864Y+008326X0180Y0200R180 S2      
317GND              VIA   -     D0100PA00X+048800Y+008980               S1      
317GND              VIA   -     D0100PA00X+047763Y+008890               S1      
317P3V3_BLAD1       VIA   -     D0100PA00X+048880Y+009380               S3      
327BLADE1_MATED_N   VIA   -           A01X+047763Y+007880X0300Y0300R180 S2      
327NNAME10007       VIA   -           A01X+048756Y+007860X0300Y0300     S2      
327SFP2_PRESENT_N   VIA   -           A01X+047179Y+007840X0300Y0300     S2      
317ENET1G_2_MDI2N   J22   -B5   D0350PA00X+048886Y+011567               S0      
317ENET1G_2_MDI1P   J22   -B3   D0350PA00X+047886Y+011567               S0      
317ENET1G_2_MDI2P   J22   -B4   D0350PA00X+048386Y+012567               S0      
317ENET1G_2_MDI0N   J22   -B2   D0350PA00X+047386Y+012567               S0      
317ENET1G_1_MDI1N   J22   -A6   D0350PA00X+047886Y+014165               S0      
317ENET1G_1_MDI2P   J22   -A4   D0350PA00X+048886Y+014165               S0      
317ENET1G_1_MDI3P   J22   -A7   D0350PA00X+047386Y+015165               S0      
317ENET1G_1_MDI2N   J22   -A5   D0350PA00X+048386Y+015165               S0      
317GND              J24   -A2   D0200PA00X+049815Y+000787               S0      
317ENET1G_1_MDI0P   J24   -A1   D0200PA00X+050602Y+000827               S0      
317GND              VIA   -     D0100PA00X+050720Y+000420               S3      
317ENET1G_1_MDI1P   J24   -E2   D0200PA00X+049815Y+002992               S0      
317ENET10G_1_RDN    J24   -E1   D0200PA00X+050602Y+003032               S0      
317GND              J24   -D2   D0200PA00X+049815Y+002441               S0      
317ENET10G_1_RDP    J24   -D1   D0200PA00X+050602Y+002480               S0      
317ENET1G_1_MDI2N   J24   -C2   D0200PA00X+049815Y+001890               S0      
317GND              J24   -C1   D0200PA00X+050602Y+001929               S0      
317ENET1G_1_MDI2P   J24   -B2   D0200PA00X+049815Y+001339               S0      
317ENET1G_1_MDI0N   J24   -B1   D0200PA00X+050602Y+001378               S0      
317SFP1_PRESENT_N   J24   -I2   D0200PA00X+049815Y+005197               S0      
317GND              J24   -I1   D0200PA00X+050602Y+005236               S0      
317NODE1_EN         J24   -H2   D0200PA00X+049815Y+004646               S0      
317ENET10G_1_TDN    J24   -H1   D0200PA00X+050602Y+004685               S0      
317GND              J24   -G2   D0200PA00X+049815Y+004095               S0      
317ENET10G_1_TDP    J24   -G1   D0200PA00X+050602Y+004134               S0      
317ENET1G_1_MDI1N   J24   -F2   D0200PA00X+049815Y+003543               S0      
317GND              J24   -F1   D0200PA00X+050602Y+003583               S0      
327ENET10G_1_LOS    R13   -2          A01X+051379Y+009156X0180Y0200R180 S2      
327P3V3_BLAD1       R13   -1          A01X+051064Y+009156X0180Y0200R180 S2      
327NNAME10009       R9    -2          A01X+051379Y+009586X0180Y0200R180 S2      
327P3V3_BLAD1       R9    -1          A01X+051064Y+009586X0180Y0200R180 S2      
327P3V3_BLAD1       R39   -2          A01X+049624Y+008721X0180Y0200R270 S2      
327NNAME10008       R39   -1          A01X+049624Y+008406X0180Y0200R270 S2      
327NNAME10008       R38   -2          A01X+050056Y+008406X0180Y0200R090 S2      
327GND              R38   -1          A01X+050056Y+008721X0180Y0200R090 S2      
327SFP1_PRESENT_N   R58   -2          A01X+050484Y+008406X0180Y0200R090 S2      
327GND              R58   -1          A01X+050484Y+008721X0180Y0200R090 S2      
327SFP1_PRESENT_N   R66   -2          A01X+051081Y+008324X0180Y0200     S2      
327NNAME10009       R66   -1          A01X+051396Y+008324X0180Y0200     S2      
327SFP1_PRESENT_N   R67   -2          A01X+051081Y+008744X0180Y0200     S2      
327ENET10G_1_LOS    R67   -1          A01X+051396Y+008744X0180Y0200     S2      
317GND              VIA   -     D0100PA00X+050570Y+009020               S3      
327NNAME10008       VIA   -           A01X+049624Y+007860X0300Y0300     S2      
327SFP1_PRESENT_N   VIA   -           A01X+050484Y+007868X0300Y0300     S2      
327ENET10G_1_SDA    R5    -2          A01X+051379Y+010446X0180Y0200R180 S2      
327P3V3_BLAD1       R5    -1          A01X+051064Y+010446X0180Y0200R180 S2      
327ENET10G_1_SCL    R7    -2          A01X+051379Y+010016X0180Y0200R180 S2      
327P3V3_BLAD1       R7    -1          A01X+051064Y+010016X0180Y0200R180 S2      
317ENET1G_2_MDI3P   J22   -B7   D0350PA00X+049886Y+011567               S0      
317P3V3_BLAD1       VIA   -     D0100PA00X+051160Y+010800               S3      
317ENET1G_2_MDI3N   J22   -B8   D0350PA00X+050386Y+012567               S0      
317ENET1G_2_MDI1N   J22   -B6   D0350PA00X+049386Y+012567               S0      
317GND              J22   -G2   D0800PA00X+051685Y+014067               S0      
317ENET1G_1_MDI0N   J22   -A2   D0350PA00X+049886Y+014165               S0      
317ENET1G_1_MDI1P   J22   -A3   D0350PA00X+049386Y+015165               S0      
317ENET1G_1_MDI0P   J22   -A1   D0350PA00X+050386Y+015165               S0      
317N/C              J22   -H1   D1280UA00X+050886Y+017665               S0      
317GND              VIA   -     D0100PA00X+052090Y+002250               S3      
317GND              VIA   -     D0100PA00X+052560Y+002260               S3      
317GND              VIA   -     D0100PA00X+052560Y+001390               S3      
317GND              VIA   -     D0100PA00X+052080Y+001380               S3      
317ENET10G_1_RDP    VIA   -     D0100PA00X+052330Y+001558               S3      
317ENET10G_1_RDN    VIA   -     D0100PA00X+052330Y+002058               S3      
317GND              J16   -19   D0370PA00X+053293Y+005038               S0      
317GND              J16   -10   D0410PA00X+053293Y+004053               S0      
317GND              J16   -18   D0370PA00X+053293Y+007006               S0      
317GND              J16   -9    D0410PA00X+053293Y+007990               S0      
317GND              J16   -17   D0370PA00X+053293Y+008856               S0      
317ENET10G_1_SDA    VIA   -     D0100PA00X+052570Y+009930               S1      
317ENET10G_1_SCL    VIA   -     D0100PA00X+051940Y+009640               S1      
317NNAME10009       VIA   -     D0100PA00X+052044Y+009100               S1      
317ENET10G_1_LOS    VIA   -     D0100PA00X+051650Y+008744               S1      
317GND              J16   -5    D0410PA00X+053293Y+011927               S0      
317GND              J22   -G1   D0800PA00X+051984Y+011567               S0      
317P12V             VIA   -     D0100PA00X+052661Y+014200               S3      
317GND              J16   -4    D0410PA00X+053293Y+015864               S0      
317GND              J22   -G3   D0800PA00X+051984Y+019464               S0      
317GND              J16   -16   D0370PA00X+054207Y+003226               S0      
317GND              J16   -15   D0370PA00X+056097Y+003226               S0      
317NNAME10010       VIA   -     D0100PA00X+055943Y+001358               S3      
327GND              U5    -14         A01X+055705Y+004051X0200Y0800R180 S2      
327GND              U5    -11         A01X+054760Y+004051X0200Y0800R180 S2      
327NNAME10010       U5    -15         A01X+056020Y+004051X0200Y0800R180 S2      
327ENET10G_1_RDN    U5    -12         A01X+055075Y+004051X0200Y0800R180 S2      
327ENET10G_1_RDP    U5    -13         A01X+055390Y+004051X0200Y0800R180 S2      
317N/C              U5    -21   D0630UA00X+054209Y+005665               S0      
317NNAME10010       VIA   -     D0100PA00X+056020Y+004610               S3      
317GND              VIA   -     D0100PA00X+055690Y+003500               S3      
317GND              VIA   -     D0100PA00X+054760Y+003500               S3      
317GND              VIA   -     D0100PA00X+055705Y+004610               S3      
317GND              VIA   -     D0100PA00X+054760Y+004610               S3      
327GND              U5    -10         A01X+054602Y+007280X0200Y0800R180 S2      
327ENET10G_1_RS1    U5    -9          A01X+054917Y+007280X0200Y0800R180 S2      
327ENET10G_1_RS0    U5    -7          A01X+055547Y+007280X0200Y0800R180 S2      
327NNAME10009       U5    -6          A01X+055862Y+007280X0200Y0800R180 S2      
327ENET10G_1_LOS    U5    -8          A01X+055232Y+007280X0200Y0800R180 S2      
317GND              J16   -8    D0410PA00X+054541Y+009959               S0      
317NNAME10009       VIA   -     D0100PA00X+055862Y+007920               S3      
317ENET10G_1_LOS    VIA   -     D0100PA00X+055232Y+007850               S3      
317GND              VIA   -     D0100PA00X+054602Y+007920               S3      
317ENET10G_1_RS1    VIA   -     D0100PA00X+054917Y+008940               S3      
317GND              J16   -2    D0410PA00X+055526Y+017833               S0      
317GND              VIA   -     D0100PA00X+057560Y+000760               S3      
317GND              VIA   -     D0100PA00X+057150Y+000750               S1      
317GND              VIA   -     D0100PA00X+056750Y+000730               S3      
317GND              VIA   -     D0100PA00X+056310Y+000720               S3      
317GND              J16   -14   D0370PA00X+057986Y+003226               S0      
327GND              C18   -2          A01X+057170Y+001043X0180Y0200R090 S2      
327NNAME10011       C18   -1          A01X+057170Y+001358X0180Y0200R090 S2      
327GND              C22   -2          A01X+056730Y+001043X0180Y0200R090 S2      
327NNAME10010       C22   -1          A01X+056730Y+001358X0180Y0200R090 S2      
327GND              C21   -2          A01X+056280Y+001043X0180Y0200R090 S2      
327NNAME10010       C21   -1          A01X+056280Y+001358X0180Y0200R090 S2      
327GND              C17   -2          A01X+057610Y+001043X0180Y0200R090 S2      
327NNAME10011       C17   -1          A01X+057610Y+001358X0180Y0200R090 S2      
317NNAME10011       VIA   -     D0100PA00X+058242Y+001647               S3      
317GND              VIA   -     D0100PA00X+056710Y+002050               S3      
317GND              VIA   -     D0100PA00X+057590Y+002080               S3      
317GND              VIA   -     D0100PA00X+057580Y+002430               S3      
317GND              VIA   -     D0100PA00X+056700Y+002440               S3      
317ENET10G_1_TDN    VIA   -     D0100PA00X+057372Y+002250               S3      
317ENET10G_1_TDP    VIA   -     D0100PA00X+056872Y+002250               S3      
327GND              U5    -20         A01X+057595Y+004051X0200Y0800R180 S2      
327GND              U5    -17         A01X+056650Y+004051X0200Y0800R180 S2      
327NNAME10011       U5    -16         A01X+056335Y+004051X0200Y0800R180 S2      
327ENET10G_1_TDN    U5    -19         A01X+057280Y+004051X0200Y0800R180 S2      
327ENET10G_1_TDP    U5    -18         A01X+056965Y+004051X0200Y0800R180 S2      
317N/C              U5    -22   D0380UA00X+057988Y+005665               S0      
317NNAME10011       VIA   -     D0100PA00X+056335Y+004610               S3      
317GND              VIA   -     D0100PA00X+057595Y+004610               S3      
317GND              VIA   -     D0100PA00X+056650Y+004610               S3      
317GND              VIA   -     D0100PA00X+057580Y+003500               S3      
317GND              VIA   -     D0100PA00X+056650Y+003500               S3      
327GND              U5    -1          A01X+057437Y+007280X0200Y0800R180 S2      
327NNAME10012       U5    -2          A01X+057122Y+007280X0200Y0800R180 S2      
327NNAME10013       U5    -3          A01X+056807Y+007280X0200Y0800R180 S2      
327ENET10G_1_SDA    U5    -4          A01X+056492Y+007280X0200Y0800R180 S2      
327ENET10G_1_SCL    U5    -5          A01X+056177Y+007280X0200Y0800R180 S2      
317GND              J16   -7    D0410PA00X+056667Y+009959               S0      
317NNAME10012       VIA   -     D0100PA00X+057122Y+007970               S3      
317NNAME10013       VIA   -     D0100PA00X+056807Y+008150               S3      
317ENET10G_1_SDA    VIA   -     D0100PA00X+056492Y+008190               S3      
317ENET10G_1_SCL    VIA   -     D0100PA00X+056177Y+008080               S3      
317GND              VIA   -     D0100PA00X+057437Y+007840               S3      
317ENET10G_1_RS0    VIA   -     D0100PA00X+056380Y+008770               S3      
317GND              J12   -2    D1580PA00X+061205Y+001969               S0      
317GND              J16   -13   D0370PA00X+058904Y+005038               S0      
317GND              J12   -1    D1580PA00X+061205Y+004185               S0      
317GND              J16   -20   D0330PA00X+058904Y+006022               S0      
317GND              J16   -12   D0370PA00X+058904Y+007006               S0      
317GND              J12   -3    D1580PA00X+061205Y+006791               S0      
317GND              J16   -6    D0410PA00X+058904Y+009959               S0      
317GND              J16   -11   D0370PA00X+058904Y+008856               S0      
317P3V3_BLAD1       VIA   -     D0100PA00X+060440Y+009600               S3      
317P3V3_BLAD1       VIA   -     D0100PA00X+060420Y+010740               S1      
317GND              J16   -3    D0410PA00X+058904Y+013896               S0      
317GND              J16   -1    D0410PA00X+058904Y+017833               S0      
327NNAME10013       R3    -2          A01X+061142Y+009514X0180Y0200R180 S2      
327P3V3_BLAD1       R3    -1          A01X+060827Y+009514X0180Y0200R180 S2      
327NNAME10012       R1    -2          A01X+061142Y+009016X0180Y0200R180 S2      
327P3V3_BLAD1       R1    -1          A01X+060827Y+009016X0180Y0200R180 S2      
327NNAME10012       R40   -2          A01X+061961Y+009016X0180Y0200     S2      
327GND              R40   -1          A01X+062276Y+009016X0180Y0200     S2      
327NNAME10013       R41   -2          A01X+061961Y+009514X0180Y0200     S2      
327GND              R41   -1          A01X+062276Y+009514X0180Y0200     S2      
317NNAME10012       VIA   -     D0100PA00X+061490Y+009016               S1      
317NNAME10013       VIA   -     D0100PA00X+061560Y+009514               S1      
317GND              VIA   -     D0100PA00X+062610Y+009990               S3      
317GND              VIA   -     D0100PA00X+062560Y+009540               S1      
317GND              VIA   -     D0100PA00X+062570Y+009010               S1      
317ENET10G_1_RS0    VIA   -     D0100PA00X+061550Y+010016               S1      
327ENET10G_1_RS1    R15   -2          A01X+061142Y+010516X0180Y0200R180 S2      
327P3V3_BLAD1       R15   -1          A01X+060827Y+010516X0180Y0200R180 S2      
327ENET10G_1_RS0    R11   -2          A01X+061142Y+010016X0180Y0200R180 S2      
327P3V3_BLAD1       R11   -1          A01X+060827Y+010016X0180Y0200R180 S2      
327ENET10G_1_RS0    R42   -2          A01X+061961Y+010016X0180Y0200     S2      
327GND              R42   -1          A01X+062276Y+010016X0180Y0200     S2      
327ENET10G_1_RS1    R43   -2          A01X+061961Y+010516X0180Y0200     S2      
327GND              R43   -1          A01X+062276Y+010516X0180Y0200     S2      
327NNAME10010       R77   -2          A01X+061814Y+012026X0440Y0540R180 S2      
327P3V3_BLAD1       R77   -1          A01X+061066Y+012026X0440Y0540R180 S2      
327NNAME10011       R76   -2          A01X+061814Y+011216X0440Y0540R180 S2      
327P3V3_BLAD1       R76   -1          A01X+061066Y+011216X0440Y0540R180 S2      
317NNAME10011       VIA   -     D0100PA00X+062266Y+011216               S1      
317NNAME10010       VIA   -     D0100PA00X+062220Y+012026               S1      
317GND              VIA   -     D0100PA00X+062660Y+010610               S3      
317ENET10G_1_RS1    VIA   -     D0100PA00X+061550Y+010516               S1      
327NNAME10010       L3    -2          A01X+061795Y+013136X0440Y0540R090 S2      
327NNAME10014       L3    -1          A01X+061795Y+013884X0440Y0540R090 S2      
327NNAME10011       L1    -2          A01X+062617Y+013136X0440Y0540R090 S2      
327NNAME10015       L1    -1          A01X+062617Y+013884X0440Y0540R090 S2      
327NNAME10014       FS3   -2          A01X+062191Y+014898X0400Y0710     S2      
327P3V3_BLAD1       FS3   -1          A01X+061049Y+014898X0400Y0710     S2      
327NNAME10015       FS1   -2          A01X+062201Y+015862X0400Y0710     S2      
327P3V3_BLAD1       FS1   -1          A01X+061060Y+015862X0400Y0710     S2      
317NNAME10015       VIA   -     D0100PA00X+062617Y+014840               S1      
317NNAME10014       VIA   -     D0100PA00X+061795Y+014700               S1      
317GND              J25   -A6   D0200PA00X+064917Y+000787               S0      
317NNAME10016       J25   -E6   D0200PA00X+064917Y+002992               S0      
317GND              J25   -D6   D0200PA00X+064917Y+002441               S0      
317NNAME10017       J25   -C6   D0200PA00X+064917Y+001890               S0      
317NNAME10018       J25   -B6   D0200PA00X+064917Y+001339               S0      
317NNAME10019       J25   -I6   D0200PA00X+064917Y+005197               S0      
317NNAME10020       J25   -H6   D0200PA00X+064917Y+004646               S0      
317GND              J25   -G6   D0200PA00X+064917Y+004095               S0      
317NNAME10021       J25   -F6   D0200PA00X+064917Y+003543               S0      
317GND              VIA   -     D0100PA00X+064830Y+005560               S3      
317GND              VIA   -     D0100PA00X+065150Y+009470               S3      
317GND              VIA   -     D0100PA00X+065110Y+009110               S3      
317GND              U10   -G3   D0990PA00X+063928Y+010862               S0      
317N/C              U3    -H1   D0630UA00X+065545Y+013224               S0      
317GND              U10   -G2   D0620PA00X+064121Y+013224               S0      
317GND              U10   -G1   D0990PA00X+063928Y+016768               S0      
317NNAME10022       J25   -A5   D0200PA00X+065705Y+000827               S0      
317GND              J25   -A4   D0200PA00X+066492Y+000787               S0      
317AIRMAX_RSVD3     J25   -A3   D0200PA00X+067280Y+000827               S0      
317GND              VIA   -     D0100PA00X+065520Y+000410               S3      
317NNAME10023       J25   -E5   D0200PA00X+065705Y+003032               S0      
317NNAME10024       J25   -E4   D0200PA00X+066492Y+002992               S0      
317NNAME10025       J25   -E3   D0200PA00X+067280Y+003032               S0      
317NNAME10026       J25   -D5   D0200PA00X+065705Y+002480               S0      
317GND              J25   -D4   D0200PA00X+066492Y+002441               S0      
317NNAME10027       J25   -D3   D0200PA00X+067280Y+002480               S0      
317GND              J25   -C5   D0200PA00X+065705Y+001929               S0      
317AIRMAX_RSVD2     J25   -C4   D0200PA00X+066492Y+001890               S0      
317GND              J25   -C3   D0200PA00X+067280Y+001929               S0      
317NNAME10028       J25   -B5   D0200PA00X+065705Y+001378               S0      
317AIRMAX_RSVD1     J25   -B4   D0200PA00X+066492Y+001339               S0      
317AIRMAX_RSVD4     J25   -B3   D0200PA00X+067280Y+001378               S0      
317GND              J25   -I5   D0200PA00X+065705Y+005236               S0      
317NNAME10029       J25   -I4   D0200PA00X+066492Y+005197               S0      
317GND              J25   -I3   D0200PA00X+067280Y+005236               S0      
317NNAME10030       J25   -H5   D0200PA00X+065705Y+004685               S0      
317NNAME10031       J25   -H4   D0200PA00X+066492Y+004646               S0      
317NNAME10032       J25   -H3   D0200PA00X+067280Y+004685               S0      
317NNAME10033       J25   -G5   D0200PA00X+065705Y+004134               S0      
317GND              J25   -G4   D0200PA00X+066492Y+004095               S0      
317NNAME10034       J25   -G3   D0200PA00X+067280Y+004134               S0      
317GND              J25   -F5   D0200PA00X+065705Y+003583               S0      
317NNAME10035       J25   -F4   D0200PA00X+066492Y+003543               S0      
317GND              J25   -F3   D0200PA00X+067280Y+003583               S0      
317GND              VIA   -     D0100PA00X+066160Y+007590               S3      
317GND              VIA   -     D0100PA00X+066720Y+007570               S3      
317GND              VIA   -     D0100PA00X+066510Y+005590               S3      
317NNAME10022       VIA   -     D0100PA00X+065931Y+007290               S1      
317NNAME10028       VIA   -     D0100PA00X+066431Y+007290               S1      
327GND              U3    -B13        A01X+066097Y+010197X0150Y0730R180 S2      
327NNAME10021       U3    -B12        A01X+066411Y+010197X0150Y0730R180 S2      
327NNAME10016       U3    -B11        A01X+066726Y+010197X0150Y0730R180 S2      
327GND              U3    -B10        A01X+067041Y+010197X0150Y0730R180 S2      
327NNAME10030       U3    -B9         A01X+067356Y+010197X0150Y0730R180 S2      
327GND              U10   -B3         A01X+067043Y+008254X0360Y0840     S2      
317NNAME10016       VIA   -     D0100PA00X+065440Y+009210               S1      
317NNAME10021       VIA   -     D0100PA00X+065440Y+009710               S1      
317GND              VIA   -     D0100PA00X+067041Y+009649               S3      
317NNAME10030       VIA   -     D0100PA00X+067264Y+009329               S1      
327GND              U3    -A13        A01X+065939Y+011185X0150Y0730R180 S2      
327NNAME10017       U3    -A12        A01X+066254Y+011185X0150Y0730R180 S2      
327NNAME10018       U3    -A11        A01X+066569Y+011185X0150Y0730R180 S2      
327GND              U3    -A10        A01X+066884Y+011185X0150Y0730R180 S2      
327NNAME10019       U3    -A9         A01X+067199Y+011185X0150Y0730R180 S2      
327NNAME10020       U3    -A8         A01X+067514Y+011185X0150Y0730R180 S2      
317NNAME10018       VIA   -     D0100PA00X+066661Y+012100               S1      
317NNAME10017       VIA   -     D0100PA00X+066161Y+012100               S1      
317GND              VIA   -     D0100PA00X+065840Y+010250               S3      
317GND              VIA   -     D0100PA00X+065939Y+011749               S3      
317GND              VIA   -     D0100PA00X+066884Y+011766               S3      
317NNAME10019       VIA   -     D0100PA00X+067106Y+012593               S1      
317NNAME10020       VIA   -     D0100PA00X+067606Y+012593               S1      
317GND              VIA   -     D0100PA00X+066750Y+012620               S3      
317GND              J25   -A2   D0200PA00X+068067Y+000787               S0      
317NNAME10036       J25   -A1   D0200PA00X+068854Y+000827               S0      
317GND              VIA   -     D0100PA00X+068880Y+000410               S3      
317NNAME10037       J25   -E2   D0200PA00X+068067Y+002992               S0      
317NNAME10038       J25   -E1   D0200PA00X+068854Y+003032               S0      
317GND              J25   -D2   D0200PA00X+068067Y+002441               S0      
317NNAME10039       J25   -D1   D0200PA00X+068854Y+002480               S0      
317NNAME10040       J25   -C2   D0200PA00X+068067Y+001890               S0      
317GND              J25   -C1   D0200PA00X+068854Y+001929               S0      
317NNAME10041       J25   -B2   D0200PA00X+068067Y+001339               S0      
317NNAME10042       J25   -B1   D0200PA00X+068854Y+001378               S0      
317NNAME10043       J25   -I2   D0200PA00X+068067Y+005197               S0      
317GND              J25   -I1   D0200PA00X+068854Y+005236               S0      
317NNAME10044       J25   -H2   D0200PA00X+068067Y+004646               S0      
317NNAME10045       J25   -H1   D0200PA00X+068854Y+004685               S0      
317GND              J25   -G2   D0200PA00X+068067Y+004095               S0      
317NNAME10046       J25   -G1   D0200PA00X+068854Y+004134               S0      
317NNAME10047       J25   -F2   D0200PA00X+068067Y+003543               S0      
317GND              J25   -F1   D0200PA00X+068854Y+003583               S0      
317GND              VIA   -     D0100PA00X+068030Y+007560               S1      
317GND              VIA   -     D0100PA00X+068160Y+005550               S3      
327NNAME10033       U3    -B8         A01X+067671Y+010197X0150Y0730R180 S2      
327GND              U3    -B7         A01X+067986Y+010197X0150Y0730R180 S2      
327NNAME10028       U3    -B6         A01X+068301Y+010197X0150Y0730R180 S2      
327NNAME10022       U3    -B5         A01X+068616Y+010197X0150Y0730R180 S2      
327GND              U3    -B4         A01X+068931Y+010197X0150Y0730R180 S2      
327NNAME10035       U3    -B3         A01X+069246Y+010197X0150Y0730R180 S2      
327NNAME10024       U3    -B2         A01X+069561Y+010197X0150Y0730R180 S2      
327GND              U10   -B2         A01X+067987Y+008254X0360Y0840     S2      
327GND              U10   -B1         A01X+068932Y+008254X0360Y0840     S2      
317GND              VIA   -     D0100PA00X+069840Y+009030               S3      
317GND              VIA   -     D0100PA00X+068972Y+008940               S1      
317GND              VIA   -     D0100PA00X+068931Y+009631               S1      
317GND              VIA   -     D0100PA00X+067986Y+009654               S3      
317NNAME10033       VIA   -     D0100PA00X+067764Y+009329               S1      
327GND              U3    -A7         A01X+067829Y+011185X0150Y0730R180 S2      
327NNAME10023       U3    -A6         A01X+068144Y+011185X0150Y0730R180 S2      
327NNAME10026       U3    -A5         A01X+068459Y+011185X0150Y0730R180 S2      
327GND              U3    -A4         A01X+068774Y+011185X0150Y0730R180 S2      
327NNAME10029       U3    -A3         A01X+069089Y+011185X0150Y0730R180 S2      
327NNAME10031       U3    -A2         A01X+069404Y+011185X0150Y0730R180 S2      
327GND              U3    -A1         A01X+069719Y+011185X0150Y0730R180 S2      
317GND              VIA   -     D0100PA00X+067829Y+012270               S3      
317GND              VIA   -     D0100PA00X+069719Y+011739               S3      
317GND              VIA   -     D0100PA00X+068774Y+011870               S3      
317NNAME10029       VIA   -     D0100PA00X+068996Y+012203               S1      
317NNAME10031       VIA   -     D0100PA00X+069496Y+012203               S1      
317GND              VIA   -     D0100PA00X+068560Y+013320               S3      
317GND              VIA   -     D0100PA00X+068090Y+013320               S3      
317NNAME10023       VIA   -     D0100PA00X+068061Y+012960               S1      
317NNAME10026       VIA   -     D0100PA00X+068561Y+012960               S1      
317AIRMAX_RSVD2     VIA   -     D0100PA00X+070110Y+001690               S1      
327AIRMAX_RSVD3     VIA   -           A01X+070261Y+005311X0300Y0300     S2      
327AIRMAX_RSVD1     VIA   -           A01X+071390Y+006050X0300Y0300     S2      
327AIRMAX_RSVD4     VIA   -           A01X+070760Y+005790X0300Y0300     S2      
327GND              U3    -B1         A01X+069876Y+010197X0150Y0730R180 S2      
317NNAME10024       VIA   -     D0100PA00X+070167Y+009710               S1      
317NNAME10035       VIA   -     D0100PA00X+070167Y+009210               S1      
317GND              VIA   -     D0100PA00X+070173Y+010197               S3      
317N/C              U3    -H2   D0630UA00X+070270Y+013224               S0      
327GND              U1    -B13        A01X+073581Y+010197X0150Y0730R180 S2      
327NNAME10032       U1    -B12        A01X+073896Y+010197X0150Y0730R180 S2      
327NNAME10034       U1    -B11        A01X+074211Y+010197X0150Y0730R180 S2      
327GND              U10   -A3         A01X+074527Y+008254X0360Y0840     S2      
317GND              VIA   -     D0100PA00X+074030Y+008730               S1      
317GND              VIA   -     D0100PA00X+073581Y+009659               S1      
317GND              VIA   -     D0100PA00X+074526Y+009604               S3      
327GND              U1    -A13        A01X+073423Y+011185X0150Y0730R180 S2      
327NNAME10025       U1    -A12        A01X+073738Y+011185X0150Y0730R180 S2      
327NNAME10027       U1    -A11        A01X+074053Y+011185X0150Y0730R180 S2      
327GND              U1    -A10        A01X+074368Y+011185X0150Y0730R180 S2      
317NNAME10034       VIA   -     D0100PA00X+072440Y+010560               S1      
317NNAME10032       VIA   -     D0100PA00X+072940Y+010560               S1      
317NNAME10025       VIA   -     D0100PA00X+073031Y+011539               S1      
317NNAME10027       VIA   -     D0100PA00X+072531Y+011539               S1      
317GND              VIA   -     D0100PA00X+074368Y+011740               S3      
317GND              VIA   -     D0100PA00X+073195Y+011185               S3      
317GND              VIA   -     D0100PA00X+072350Y+011890               S3      
317GND              VIA   -     D0100PA00X+072240Y+010230               S3      
317GND              VIA   -     D0100PA00X+073090Y+010890               S3      
317N/C              U1    -H1   D0630UA00X+073030Y+013224               S0      
317GND              VIA   -     D0100PA00X+075310Y+007510               S3      
317GND              VIA   -     D0100PA00X+076560Y+007480               S3      
317NNAME10046       VIA   -     D0100PA00X+076193Y+007290               S1      
317NNAME10045       VIA   -     D0100PA00X+075693Y+007290               S1      
327GND              U1    -B10        A01X+074526Y+010197X0150Y0730R180 S2      
327NNAME10047       U1    -B9         A01X+074841Y+010197X0150Y0730R180 S2      
327NNAME10037       U1    -B8         A01X+075156Y+010197X0150Y0730R180 S2      
327GND              U1    -B7         A01X+075470Y+010197X0150Y0730R180 S2      
327NNAME10045       U1    -B6         A01X+075785Y+010197X0150Y0730R180 S2      
327NNAME10046       U1    -B5         A01X+076100Y+010197X0150Y0730R180 S2      
327GND              U1    -B4         A01X+076415Y+010197X0150Y0730R180 S2      
327NNAME10042       U1    -B3         A01X+076730Y+010197X0150Y0730R180 S2      
327GND              U10   -A2         A01X+075472Y+008254X0360Y0840     S2      
327GND              U10   -A1         A01X+076417Y+008254X0360Y0840     S2      
317NNAME10037       VIA   -     D0100PA00X+075248Y+009283               S1      
317NNAME10047       VIA   -     D0100PA00X+074748Y+009283               S1      
317GND              VIA   -     D0100PA00X+076415Y+009615               S1      
317GND              VIA   -     D0100PA00X+075470Y+009620               S3      
327NNAME10040       U1    -A9         A01X+074683Y+011185X0150Y0730R180 S2      
327NNAME10041       U1    -A8         A01X+074998Y+011185X0150Y0730R180 S2      
327GND              U1    -A7         A01X+075313Y+011185X0150Y0730R180 S2      
327NNAME10043       U1    -A6         A01X+075628Y+011185X0150Y0730R180 S2      
327NNAME10044       U1    -A5         A01X+075943Y+011185X0150Y0730R180 S2      
327GND              U1    -A4         A01X+076258Y+011185X0150Y0730R180 S2      
327NNAME10038       U1    -A3         A01X+076573Y+011185X0150Y0730R180 S2      
317NNAME10040       VIA   -     D0100PA00X+074591Y+012045               S1      
317NNAME10041       VIA   -     D0100PA00X+075091Y+012045               S1      
317GND              VIA   -     D0100PA00X+076258Y+011730               S3      
317GND              VIA   -     D0100PA00X+075313Y+011730               S3      
317GND              VIA   -     D0100PA00X+075430Y+012140               S3      
317NNAME10038       VIA   -     D0100PA00X+076480Y+012033               S1      
317GND              VIA   -     D0100PA00X+076400Y+012470               S3      
317NNAME10044       VIA   -     D0100PA00X+076041Y+012473               S1      
317NNAME10043       VIA   -     D0100PA00X+075541Y+012473               S1      
317N/C              H1    -1    D1380UA00X+078366Y+001850               S0      
327NNAME10036       U1    -B2         A01X+077045Y+010197X0150Y0730R180 S2      
327GND              U1    -B1         A01X+077360Y+010197X0150Y0730R180 S2      
317GND              VIA   -     D0100PA00X+077460Y+009030               S3      
317NNAME10042       VIA   -     D0100PA00X+077820Y+009213               S1      
317NNAME10036       VIA   -     D0100PA00X+077820Y+009713               S1      
327NNAME10039       U1    -A2         A01X+076888Y+011185X0150Y0730R180 S2      
327GND              U1    -A1         A01X+077203Y+011185X0150Y0730R180 S2      
317GND              U10   -G6   D0990PA00X+079369Y+010862               S0      
317GND              VIA   -     D0100PA00X+077603Y+010197               S1      
317GND              VIA   -     D0100PA00X+077203Y+011730               S3      
317NNAME10039       VIA   -     D0100PA00X+076980Y+012033               S1      
317N/C              U1    -H2   D0630UA00X+077754Y+013224               S0      
317GND              U10   -G5   D0620PA00X+079176Y+013224               S0      
317GND              U10   -G4   D0990PA00X+079369Y+016768               S0      
317GND              VIA   -     D0200PA00X+080680Y+002670               S3      
317P12V             VIA   -     D0200PA00X+081370Y+004390               S3      
317GND              VIA   -     D0200PA00X+081070Y+006520               S3      
317P12V             VIA   -     D0200PA00X+080970Y+008650               S3      
317GND              VIA   -     D0200PA00X+083680Y+002670               S3      
317GND              VIA   -     D0200PA00X+082520Y+011170               S3      
317N/C              H4    -1    D1380UA00X+082602Y+016339               S0      
317GND              VIA   -     D0200PA00X+084070Y+006520               S3      
317P12V             VIA   -     D0200PA00X+083970Y+008650               S3      
317GND              VIA   -     D0200PA00X+085520Y+011170               S3      
317P12V             VIA   -     D0200PA00X+083830Y+012810               S3      
317P12V             VIA   -     D0200PA00X+085540Y+015240               S3      
317P12V             VIA   -     D0200PA00X+085700Y+018980               S3      
317GND              VIA   -     D0200PA00X+085540Y+017300               S3      
317GND              VIA   -     D0200PA00X+086680Y+002670               S3      
317GND              VIA   -     D0200PA00X+087070Y+006520               S3      
317P12V             VIA   -     D0200PA00X+086970Y+008650               S3      
317P12V             VIA   -     D0200PA00X+086830Y+012810               S3      
317GND              VIA   -     D0200PA00X+089680Y+002670               S3      
317GND              VIA   -     D0200PA00X+090070Y+006520               S3      
317P12V             VIA   -     D0200PA00X+089970Y+008650               S3      
317GND              VIA   -     D0200PA00X+088520Y+011170               S3      
317P12V             VIA   -     D0200PA00X+089830Y+012810               S3      
317P12V             VIA   -     D0200PA00X+088540Y+015240               S3      
317P12V             VIA   -     D0200PA00X+088700Y+018980               S3      
317GND              VIA   -     D0200PA00X+088540Y+017300               S3      
317GND              VIA   -     D0200PA00X+092680Y+002670               S3      
317P12V             VIA   -     D0200PA00X+092970Y+008650               S3      
317GND              VIA   -     D0200PA00X+091520Y+011170               S3      
317P12V             VIA   -     D0200PA00X+092830Y+012810               S3      
317P12V             VIA   -     D0200PA00X+091540Y+015240               S3      
317P12V             VIA   -     D0200PA00X+091700Y+018980               S3      
317GND              VIA   -     D0200PA00X+091540Y+017300               S3      
317GND              VIA   -     D0200PA00X+093070Y+006520               S3      
317GND              VIA   -     D0200PA00X+094520Y+011170               S3      
317P12V             VIA   -     D0200PA00X+094540Y+015240               S3      
317P12V             VIA   -     D0200PA00X+094700Y+018980               S3      
317GND              VIA   -     D0200PA00X+094540Y+017300               S3      
317P12V             VIA   -     D0200PA00X+095900Y+001800               S3      
317GND              VIA   -     D0200PA00X+095680Y+002670               S3      
317GND              VIA   -     D0200PA00X+096070Y+006520               S3      
317P12V             VIA   -     D0200PA00X+095970Y+008650               S3      
317GND              VIA   -     D0200PA00X+097520Y+011170               S3      
317P12V             VIA   -     D0200PA00X+095830Y+012810               S3      
317P12V             VIA   -     D0200PA00X+097540Y+015240               S3      
317GND              VIA   -     D0200PA00X+097540Y+017300               S3      
317GND              VIA   -     D0200PA00X+098680Y+002670               S3      
317GND              VIA   -     D0200PA00X+099070Y+006520               S3      
317P12V             VIA   -     D0200PA00X+098970Y+008650               S3      
317P12V             VIA   -     D0200PA00X+098830Y+012810               S3      
317P12V             VIA   -     D0200PA00X+097700Y+018980               S3      
317GND              VIA   -     D0200PA00X+101880Y+002630               S3      
327N/C                    -           A01X+100970Y+008150X0400Y0400     S2      
327N/C                    -           A08X+100980Y+008130X0400Y0400     S1      
317GND              VIA   -     D0200PA00X+100520Y+011170               S3      
317P12V             VIA   -     D0200PA00X+101830Y+012810               S3      
317P12V             VIA   -     D0200PA00X+100540Y+015240               S3      
317P12V             VIA   -     D0200PA00X+100700Y+018980               S3      
317GND              VIA   -     D0200PA00X+100540Y+017300               S3      
317P12V             VIA   -     D0200PA00X+104300Y+004550               S3      
317GND              VIA   -     D0200PA00X+102270Y+006480               S3      
317P12V             VIA   -     D0200PA00X+103190Y+008410               S3      
317GND              VIA   -     D0200PA00X+103720Y+011130               S3      
317P12V             VIA   -     D0200PA00X+103540Y+015240               S3      
317P12V             VIA   -     D0200PA00X+103700Y+018980               S3      
317GND              VIA   -     D0200PA00X+103540Y+017300               S3      
317P12V             VIA   -     D0200PA00X+106370Y+001530               S3      
317GND              VIA   -     D0200PA00X+104880Y+002630               S3      
317GND              VIA   -     D0200PA00X+105270Y+006480               S3      
317P12V             VIA   -     D0200PA00X+106190Y+008410               S3      
317GND              VIA   -     D0200PA00X+106720Y+011130               S3      
317P12V             VIA   -     D0200PA00X+104830Y+012810               S3      
317P12V             VIA   -     D0200PA00X+106540Y+015240               S3      
317P12V             VIA   -     D0200PA00X+106700Y+018980               S3      
317GND              VIA   -     D0200PA00X+106740Y+017260               S3      
317GND              VIA   -     D0200PA00X+107880Y+002630               S3      
317P12V             VIA   -     D0200PA00X+107300Y+004550               S3      
317GND              VIA   -     D0200PA00X+108270Y+006480               S3      
317P12V             VIA   -     D0200PA00X+107830Y+012810               S3      
317N/C              H2    -1    D1380UA00X+110162Y+001850               S0      
317P12V             VIA   -     D0200PA00X+109190Y+008410               S3      
317GND              VIA   -     D0200PA00X+109720Y+011130               S3      
317P12V             VIA   -     D0200PA00X+110830Y+012810               S3      
317P12V             VIA   -     D0200PA00X+109540Y+015240               S3      
317P12V             VIA   -     D0200PA00X+109700Y+018980               S3      
317GND              VIA   -     D0200PA00X+109740Y+017260               S3      
317GND              VIA   -     D0200PA00X+113660Y+001970               S3      
317GND              VIA   -     D0200PA00X+113540Y+004100               S3      
317P12V             VIA   -     D0200PA00X+112090Y+006450               S3      
317P12V             VIA   -     D0200PA00X+112190Y+008410               S3      
317GND              VIA   -     D0200PA00X+112720Y+011130               S3      
317P12V             VIA   -     D0200PA00X+112540Y+015240               S3      
317P12V             VIA   -     D0200PA00X+112700Y+018980               S3      
317GND              VIA   -     D0200PA00X+112740Y+017260               S3      
317P12V             VIA   -     D0200PA00X+114710Y+006450               S3      
317P12V             VIA   -     D0200PA00X+115190Y+008410               S3      
317P12V             VIA   -     D0200PA00X+115540Y+015240               S3      
317P12V             VIA   -     D0200PA00X+115700Y+018980               S3      
317GND              VIA   -     D0200PA00X+115740Y+017260               S3      
317GND              J5    -2    D1580PA00X+117685Y+001969               S0      
317GND              J5    -1    D1580PA00X+117685Y+004185               S0      
317GND              J5    -3    D1580PA00X+117685Y+006791               S0      
317N/C              H6    -1    D1380UA00X+118429Y+016339               S0      
317GND              J9    -D3   D0300PA00X+120598Y+001181               S0      
317GND              J9    -D2   D0300PA00X+120598Y+001968               S0      
317GND              J9    -D1   D0300PA00X+120598Y+002756               S0      
317GND              J9    -A3   D0300PA00X+120598Y+004331               S0      
317GND              J9    -A2   D0300PA00X+120598Y+005118               S0      
317GND              J9    -A1   D0300PA00X+120598Y+005905               S0      
327NNAME10048       L8    -2          A01X+120600Y+012876X0440Y0540R090 S2      
327NNAME10049       L8    -1          A01X+120600Y+013624X0440Y0540R090 S2      
317GND              J9    -D6   D0300PA00X+121386Y+001181               S0      
317GND              J9    -D5   D0300PA00X+121386Y+001968               S0      
317GND              J9    -D4   D0300PA00X+121386Y+002756               S0      
317P12V             J9    -C6   D0300PA00X+122961Y+001181               S0      
317P12V             J9    -C5   D0300PA00X+122961Y+001968               S0      
317P12V             J9    -C4   D0300PA00X+122961Y+002756               S0      
317P12V             J9    -B6   D0300PA00X+122961Y+004331               S0      
317P12V             J9    -B5   D0300PA00X+122961Y+005118               S0      
317GND              J9    -A6   D0300PA00X+121386Y+004331               S0      
317GND              J9    -A5   D0300PA00X+121386Y+005118               S0      
317N/C              J9    -H1   D0850UA00X+122173Y+003740               S0      
317P12V             J9    -B4   D0300PA00X+122961Y+005905               S0      
317GND              J9    -A4   D0300PA00X+121386Y+005905               S0      
327P12V             C10   -1          A01X+121732Y+008970X0280Y0320     S2      
327GND              C10   -2          A01X+121732Y+009550X0280Y0320     S2      
327GND              C9    -2          A01X+122342Y+009550X0280Y0320     S2      
327P12V             C9    -1          A01X+122342Y+008970X0280Y0320     S2      
317GND              VIA   -     D0100PA00X+122320Y+009900               S1      
317GND              VIA   -     D0100PA00X+121800Y+009910               S3      
327ENET10G_4_RS0    R52   -2          A01X+122326Y+010836X0180Y0200R180 S2      
327GND              R52   -1          A01X+122011Y+010836X0180Y0200R180 S2      
327ENET10G_4_RS1    R53   -2          A01X+122326Y+010286X0180Y0200R180 S2      
327GND              R53   -1          A01X+122011Y+010286X0180Y0200R180 S2      
327NNAME10050       R54   -2          A01X+122326Y+011956X0180Y0200R180 S2      
327GND              R54   -1          A01X+122011Y+011956X0180Y0200R180 S2      
327NNAME10051       R55   -2          A01X+122326Y+011404X0180Y0200R180 S2      
327GND              R55   -1          A01X+122011Y+011404X0180Y0200R180 S2      
317GND              VIA   -     D0100PA00X+121650Y+011950               S1      
317GND              VIA   -     D0100PA00X+121670Y+011440               S1      
317GND              VIA   -     D0100PA00X+121650Y+010830               S1      
317GND              VIA   -     D0100PA00X+121640Y+010260               S1      
317NNAME10050       VIA   -     D0100PA00X+122690Y+011956               S1      
317NNAME10051       VIA   -     D0100PA00X+122690Y+011404               S1      
317ENET10G_4_RS0    VIA   -     D0100PA00X+122700Y+010836               S1      
317ENET10G_4_RS1    VIA   -     D0100PA00X+122710Y+010286               S1      
327NNAME10052       FS6   -2          A01X+122220Y+014390X0400Y0710R180 S2      
327NNAME10053       L6    -2          A01X+121410Y+012886X0440Y0540R090 S2      
327NNAME10052       L6    -1          A01X+121410Y+013634X0440Y0540R090 S2      
327NNAME10048       R83   -2          A01X+122516Y+012624X0440Y0540     S2      
327NNAME10053       R82   -2          A01X+122516Y+013454X0440Y0540     S2      
317NNAME10053       VIA   -     D0100PA00X+121960Y+012940               S1      
317NNAME10048       VIA   -     D0100PA00X+121940Y+012390               S1      
317NNAME10049       VIA   -     D0100PA00X+121120Y+014490               S1      
317NNAME10052       VIA   -     D0100PA00X+121741Y+014390               S1      
327NNAME10049       FS8   -2          A01X+122230Y+015361X0400Y0710R180 S2      
317P12V             J9    -C3   D0300PA00X+123748Y+001181               S0      
317P12V             J9    -C2   D0300PA00X+123748Y+001968               S0      
317P12V             J9    -C1   D0300PA00X+123748Y+002756               S0      
317P12V             J9    -B3   D0300PA00X+123748Y+004331               S0      
317P12V             J9    -B2   D0300PA00X+123748Y+005118               S0      
317GND              J18   -10   D0410PA00X+125372Y+004053               S0      
317P12V             J9    -B1   D0300PA00X+123748Y+005905               S0      
317GND              J18   -9    D0410PA00X+125372Y+007990               S0      
327GND              C12   -2          A01X+122932Y+009357X0180Y0200R270 S2      
327P12V             C12   -1          A01X+122932Y+009042X0180Y0200R270 S2      
327GND              C11   -2          A01X+123352Y+009357X0180Y0200R270 S2      
327P12V             C11   -1          A01X+123352Y+009042X0180Y0200R270 S2      
317GND              VIA   -     D0100PA00X+122980Y+009640               S1      
317GND              J18   -5    D0410PA00X+125372Y+011927               S0      
327NNAME10050       R18   -2          A01X+123099Y+011956X0180Y0200     S2      
327P3V3_BLAD2       R18   -1          A01X+123414Y+011956X0180Y0200     S2      
327NNAME10051       R20   -2          A01X+123099Y+011404X0180Y0200     S2      
327P3V3_BLAD2       R20   -1          A01X+123414Y+011404X0180Y0200     S2      
327ENET10G_4_RS0    R28   -2          A01X+123099Y+010836X0180Y0200     S2      
327P3V3_BLAD2       R28   -1          A01X+123414Y+010836X0180Y0200     S2      
327ENET10G_4_RS1    R32   -2          A01X+123099Y+010286X0180Y0200     S2      
327P3V3_BLAD2       R32   -1          A01X+123414Y+010286X0180Y0200     S2      
317P3V3_BLAD2       VIA   -     D0100PA00X+123890Y+012330               S3      
327P3V3_BLAD2       FS6   -1          A01X+123362Y+014390X0400Y0710R180 S2      
327P3V3_BLAD2       R83   -1          A01X+123264Y+012624X0440Y0540     S2      
327P3V3_BLAD2       R82   -1          A01X+123264Y+013454X0440Y0540     S2      
317P3V3_BLAD2       VIA   -     D0100PA00X+123810Y+012790               S1      
317GND              J18   -4    D0410PA00X+125372Y+015864               S0      
327P3V3_BLAD2       FS8   -1          A01X+123372Y+015361X0400Y0710R180 S2      
317GND              VIA   -     D0100PA00X+127300Y+000610               S3      
317GND              J18   -16   D0370PA00X+126286Y+003226               S0      
327GND              C31   -2          A01X+127260Y+000883X0180Y0200R090 S2      
327NNAME10048       C31   -1          A01X+127260Y+001198X0180Y0200R090 S2      
317ENET10G_4_RDN    VIA   -     D0100PA00X+127061Y+002196               S3      
317GND              VIA   -     D0100PA00X+126770Y+002290               S3      
317GND              VIA   -     D0100PA00X+126770Y+001970               S3      
317NNAME10048       VIA   -     D0100PA00X+126870Y+001400               S3      
327GND              U8    -11         A01X+126839Y+004051X0200Y0800R180 S2      
327ENET10G_4_RDN    U8    -12         A01X+127154Y+004051X0200Y0800R180 S2      
327ENET10G_4_RDP    U8    -13         A01X+127469Y+004051X0200Y0800R180 S2      
317N/C              U8    -21   D0630UA00X+126287Y+005665               S0      
317GND              J18   -19   D0370PA00X+125372Y+005038               S0      
317GND              VIA   -     D0100PA00X+126839Y+003500               S3      
317GND              VIA   -     D0100PA00X+126839Y+004610               S3      
327GND              U8    -10         A01X+126681Y+007280X0200Y0800R180 S2      
327ENET10G_4_RS1    U8    -9          A01X+126996Y+007280X0200Y0800R180 S2      
327ENET10G_4_LOS    U8    -8          A01X+127311Y+007280X0200Y0800R180 S2      
317GND              J18   -18   D0370PA00X+125372Y+007006               S0      
317GND              J18   -8    D0410PA00X+126620Y+009959               S0      
317GND              J18   -17   D0370PA00X+125372Y+008856               S0      
317GND              VIA   -     D0100PA00X+126681Y+007830               S3      
317ENET10G_4_LOS    VIA   -     D0100PA00X+127311Y+008910               S3      
317ENET10G_4_RS1    VIA   -     D0100PA00X+126996Y+007840               S3      
317GND              J18   -2    D0410PA00X+127604Y+017833               S0      
317GND              VIA   -     D0100PA00X+127670Y+000590               S3      
317GND              VIA   -     D0100PA00X+128090Y+000590               S3      
317GND              VIA   -     D0100PA00X+128580Y+000590               S3      
317GND              J18   -15   D0370PA00X+128175Y+003226               S0      
327GND              C28   -2          A01X+128160Y+000883X0180Y0200R090 S2      
327NNAME10053       C28   -1          A01X+128160Y+001198X0180Y0200R090 S2      
327GND              C32   -2          A01X+127700Y+000883X0180Y0200R090 S2      
327NNAME10048       C32   -1          A01X+127700Y+001198X0180Y0200R090 S2      
327GND              C27   -2          A01X+128600Y+000883X0180Y0200R090 S2      
327NNAME10053       C27   -1          A01X+128600Y+001198X0180Y0200R090 S2      
317GND              VIA   -     D0100PA00X+127870Y+001980               S3      
317GND              VIA   -     D0100PA00X+127870Y+002300               S3      
317ENET10G_4_RDP    VIA   -     D0100PA00X+127561Y+002196               S3      
317NNAME10053       VIA   -     D0100PA00X+128978Y+001198               S3      
327GND              U8    -20         A01X+129673Y+004051X0200Y0800R180 S2      
327GND              U8    -17         A01X+128728Y+004051X0200Y0800R180 S2      
327GND              U8    -14         A01X+127784Y+004051X0200Y0800R180 S2      
327NNAME10053       U8    -16         A01X+128413Y+004051X0200Y0800R180 S2      
327NNAME10048       U8    -15         A01X+128099Y+004051X0200Y0800R180 S2      
327ENET10G_4_TDN    U8    -19         A01X+129358Y+004051X0200Y0800R180 S2      
327ENET10G_4_TDP    U8    -18         A01X+129043Y+004051X0200Y0800R180 S2      
317GND              VIA   -     D0100PA00X+129660Y+003500               S3      
317GND              VIA   -     D0100PA00X+127770Y+003500               S3      
317GND              VIA   -     D0100PA00X+128728Y+003500               S3      
317GND              VIA   -     D0100PA00X+129673Y+004610               S3      
317GND              VIA   -     D0100PA00X+128728Y+004610               S3      
317GND              VIA   -     D0100PA00X+127784Y+004610               S3      
317NNAME10053       VIA   -     D0100PA00X+128413Y+004610               S3      
317NNAME10048       VIA   -     D0100PA00X+128099Y+004620               S3      
327GND              U8    -1          A01X+129516Y+007280X0200Y0800R180 S2      
327NNAME10050       U8    -2          A01X+129201Y+007280X0200Y0800R180 S2      
327NNAME10051       U8    -3          A01X+128886Y+007280X0200Y0800R180 S2      
327ENET10G_4_RS0    U8    -7          A01X+127626Y+007280X0200Y0800R180 S2      
327ENET10G_4_SDA    U8    -4          A01X+128571Y+007280X0200Y0800R180 S2      
327ENET10G_4_SCL    U8    -5          A01X+128256Y+007280X0200Y0800R180 S2      
327NNAME10054       U8    -6          A01X+127941Y+007280X0200Y0800R180 S2      
317GND              J18   -7    D0410PA00X+128746Y+009959               S0      
317GND              VIA   -     D0100PA00X+129516Y+007916               S3      
317NNAME10050       VIA   -     D0100PA00X+129201Y+008019               S3      
317NNAME10051       VIA   -     D0100PA00X+128886Y+007840               S3      
317NNAME10054       VIA   -     D0100PA00X+127941Y+008720               S3      
317ENET10G_4_SDA    VIA   -     D0100PA00X+128571Y+008430               S3      
317ENET10G_4_RS0    VIA   -     D0100PA00X+127626Y+007900               S3      
317ENET10G_4_SCL    VIA   -     D0100PA00X+128256Y+008570               S3      
317GND              J18   -14   D0370PA00X+130065Y+003226               S0      
317N/C              U8    -22   D0380UA00X+130067Y+005665               S0      
317GND              J18   -13   D0370PA00X+130982Y+005038               S0      
317GND              VIA   -     D0100PA00X+131588Y+003820               S3      
317GND              VIA   -     D0100PA00X+131598Y+003390               S3      
317ENET10G_4_TDN    VIA   -     D0100PA00X+131796Y+003620               S3      
317GND              J18   -20   D0330PA00X+130982Y+006022               S0      
317GND              J18   -12   D0370PA00X+130982Y+007006               S0      
317GND              J18   -6    D0410PA00X+130982Y+009959               S0      
317GND              J18   -11   D0370PA00X+130982Y+008856               S0      
317GND              J18   -3    D0410PA00X+130982Y+013896               S0      
317GND              J23   -G6   D0800PA00X+132295Y+013165               S0      
317GND              J18   -1    D0410PA00X+130982Y+017833               S0      
317GND              J23   -G4   D0800PA00X+132295Y+019464               S0      
317GND              J7    -A6   D0200PA00X+133673Y+000787               S0      
317ENET1G_4_MDI1P   J7    -A5   D0200PA00X+134461Y+000827               S0      
317ENET10G_4_RDP    J7    -E6   D0200PA00X+133673Y+002992               S0      
317ENET1G_4_MDI2N   J7    -E5   D0200PA00X+134461Y+003032               S0      
317GND              J7    -D6   D0200PA00X+133673Y+002441               S0      
317ENET1G_4_MDI2P   J7    -D5   D0200PA00X+134461Y+002480               S0      
317ENET1G_4_MDI3N   J7    -C6   D0200PA00X+133673Y+001890               S0      
317GND              J7    -C5   D0200PA00X+134461Y+001929               S0      
317ENET1G_4_MDI3P   J7    -B6   D0200PA00X+133673Y+001339               S0      
317ENET1G_4_MDI1N   J7    -B5   D0200PA00X+134461Y+001378               S0      
317ENET10G_4_TDN    J7    -I6   D0200PA00X+133673Y+005197               S0      
317BLADE2_MATED_N   J7    -I5   D0200PA00X+134461Y+005236               S0      
317ENET10G_4_TDP    J7    -H6   D0200PA00X+133673Y+004646               S0      
317SFP4_PRESENT_N   J7    -H5   D0200PA00X+134461Y+004685               S0      
317GND              J7    -G6   D0200PA00X+133673Y+004095               S0      
317NODE4_EN         J7    -G5   D0200PA00X+134461Y+004134               S0      
317ENET10G_4_RDN    J7    -F6   D0200PA00X+133673Y+003543               S0      
317GND              J7    -F5   D0200PA00X+134461Y+003583               S0      
317ENET10G_4_TDP    VIA   -     D0100PA00X+132356Y+003620               S3      
317GND              VIA   -     D0100PA00X+132528Y+003860               S3      
317GND              VIA   -     D0100PA00X+132528Y+003380               S3      
317GND              VIA   -     D0100PA00X+133530Y+005560               S3      
327ENET10G_4_SDA    R22   -2          A01X+132964Y+008584X0180Y0200     S2      
327P3V3_BLAD2       R22   -1          A01X+133279Y+008584X0180Y0200     S2      
327ENET10G_4_SCL    R24   -2          A01X+132964Y+009034X0180Y0200     S2      
327P3V3_BLAD2       R24   -1          A01X+133279Y+009034X0180Y0200     S2      
327NNAME10054       R26   -2          A01X+132964Y+009464X0180Y0200     S2      
327P3V3_BLAD2       R26   -1          A01X+133279Y+009464X0180Y0200     S2      
327ENET10G_4_LOS    R30   -2          A01X+132974Y+009924X0180Y0200     S2      
327P3V3_BLAD2       R30   -1          A01X+133289Y+009924X0180Y0200     S2      
327SFP4_PRESENT_N   R73   -2          A01X+134119Y+008326X0180Y0200R180 S2      
327NNAME10054       R73   -1          A01X+133804Y+008326X0180Y0200R180 S2      
327SFP4_PRESENT_N   R72   -2          A01X+134119Y+008756X0180Y0200R180 S2      
327ENET10G_4_LOS    R72   -1          A01X+133804Y+008756X0180Y0200R180 S2      
317GND              VIA   -     D0100PA00X+134040Y+009080               S3      
317ENET10G_4_LOS    VIA   -     D0100PA00X+133340Y+008290               S3      
317ENET10G_4_LOS    VIA   -     D0100PA00X+132300Y+009924               S1      
317NNAME10054       VIA   -     D0100PA00X+132140Y+009280               S1      
317NNAME10054       VIA   -     D0100PA00X+132950Y+008140               S3      
317ENET10G_4_SDA    VIA   -     D0100PA00X+132150Y+008260               S1      
317ENET10G_4_SCL    VIA   -     D0100PA00X+132250Y+008780               S1      
317P3V3_BLAD2       VIA   -     D0100PA00X+133560Y+009650               S3      
327SFP4_PRESENT_N   VIA   -           A01X+134119Y+007840X0300Y0300     S2      
317ENET1G_4_MDI0P   J23   -B1   D0350PA00X+133894Y+011567               S0      
317ENET1G_4_MDI0N   J23   -B2   D0350PA00X+134394Y+012567               S0      
317ENET1G_3_MDI3N   J23   -A8   D0350PA00X+133894Y+014165               S0      
317GND              J23   -G5   D0800PA00X+132595Y+015366               S0      
317ENET1G_3_MDI3P   J23   -A7   D0350PA00X+134394Y+015165               S0      
317N/C              J23   -H2   D1280UA00X+133394Y+017665               S0      
317GND              J7    -A4   D0200PA00X+135248Y+000787               S0      
317ENET1G_3_MDI3P   J7    -A3   D0200PA00X+136036Y+000827               S0      
317GND              VIA   -     D0100PA00X+136060Y+000400               S3      
317GND              VIA   -     D0100PA00X+134470Y+000410               S3      
317ENET10G_4_SDA    J7    -E4   D0200PA00X+135248Y+002992               S0      
317ENET10G_3_SCL    J7    -E3   D0200PA00X+136036Y+003032               S0      
317GND              J7    -D4   D0200PA00X+135248Y+002441               S0      
317ENET10G_3_SDA    J7    -D3   D0200PA00X+136036Y+002480               S0      
317ENET1G_4_MDI0N   J7    -C4   D0200PA00X+135248Y+001890               S0      
317GND              J7    -C3   D0200PA00X+136036Y+001929               S0      
317ENET1G_4_MDI0P   J7    -B4   D0200PA00X+135248Y+001339               S0      
317ENET1G_3_MDI3N   J7    -B3   D0200PA00X+136036Y+001378               S0      
317NNAME10055       J7    -I4   D0200PA00X+135248Y+005197               S0      
317P3V3_BLAD2       J7    -I3   D0200PA00X+136036Y+005236               S0      
317NODE4_TXD        J7    -H4   D0200PA00X+135248Y+004646               S0      
317NODE3_TXD        J7    -H3   D0200PA00X+136036Y+004685               S0      
317NODE4_RXD        J7    -G4   D0200PA00X+135248Y+004095               S0      
317NODE3_RXD        J7    -G3   D0200PA00X+136036Y+004134               S0      
317ENET10G_4_SCL    J7    -F4   D0200PA00X+135248Y+003543               S0      
317NNAME10056       J7    -F3   D0200PA00X+136036Y+003583               S0      
317NODE3_TXD        VIA   -     D0100PA00X+135820Y+006900               S3      
317P3V3_BLAD2       VIA   -     D0100PA00X+135860Y+007370               S3      
327BLADE2_MATED_N   R36   -2          A01X+135026Y+008419X0180Y0200R090 S2      
327GND              R36   -1          A01X+135026Y+008734X0180Y0200R090 S2      
327P3V3_BLAD2       R61   -2          A01X+135564Y+008691X0180Y0200R270 S2      
327NNAME10055       R61   -1          A01X+135564Y+008376X0180Y0200R270 S2      
327NNAME10055       R60   -2          A01X+135994Y+008376X0180Y0200R090 S2      
327GND              R60   -1          A01X+135994Y+008691X0180Y0200R090 S2      
327NNAME10056       R64   -2          A01X+136426Y+008369X0180Y0200R090 S2      
327GND              R64   -1          A01X+136426Y+008684X0180Y0200R090 S2      
327SFP4_PRESENT_N   R74   -2          A01X+134556Y+008421X0180Y0200R090 S2      
327GND              R74   -1          A01X+134556Y+008736X0180Y0200R090 S2      
317GND              VIA   -     D0100PA00X+135900Y+009100               S1      
327BLADE2_MATED_N   VIA   -           A01X+134830Y+007850X0300Y0300     S2      
327NNAME10055       VIA   -           A01X+135770Y+007870X0300Y0300     S2      
327NNAME10056       VIA   -           A01X+136426Y+007870X0300Y0300     S2      
317ENET1G_4_MDI2N   J23   -B5   D0350PA00X+135894Y+011567               S0      
317ENET1G_4_MDI1P   J23   -B3   D0350PA00X+134894Y+011567               S0      
317P3V3_BLAD2       VIA   -     D0100PA00X+134510Y+010550               S3      
317ENET1G_4_MDI1N   J23   -B6   D0350PA00X+136394Y+012567               S0      
317ENET1G_4_MDI2P   J23   -B4   D0350PA00X+135394Y+012567               S0      
317ENET1G_3_MDI1N   J23   -A6   D0350PA00X+134894Y+014165               S0      
317ENET1G_3_MDI2P   J23   -A4   D0350PA00X+135894Y+014165               S0      
317ENET1G_3_MDI2N   J23   -A5   D0350PA00X+135394Y+015165               S0      
317ENET1G_3_MDI1P   J23   -A3   D0350PA00X+136394Y+015165               S0      
317GND              J7    -A2   D0200PA00X+136823Y+000787               S0      
317ENET1G_3_MDI0P   J7    -A1   D0200PA00X+137610Y+000827               S0      
317GND              VIA   -     D0100PA00X+137630Y+000400               S3      
317ENET1G_3_MDI1P   J7    -E2   D0200PA00X+136823Y+002992               S0      
317ENET10G_3_RDN    J7    -E1   D0200PA00X+137610Y+003032               S0      
317GND              J7    -D2   D0200PA00X+136823Y+002441               S0      
317ENET10G_3_RDP    J7    -D1   D0200PA00X+137610Y+002480               S0      
317ENET1G_3_MDI2N   J7    -C2   D0200PA00X+136823Y+001890               S0      
317GND              J7    -C1   D0200PA00X+137610Y+001929               S0      
317ENET1G_3_MDI2P   J7    -B2   D0200PA00X+136823Y+001339               S0      
317ENET1G_3_MDI0N   J7    -B1   D0200PA00X+137610Y+001378               S0      
317SFP3_PRESENT_N   J7    -I2   D0200PA00X+136823Y+005197               S0      
317GND              J7    -I1   D0200PA00X+137610Y+005236               S0      
317NODE3_EN         J7    -H2   D0200PA00X+136823Y+004646               S0      
317ENET10G_3_TDN    J7    -H1   D0200PA00X+137610Y+004685               S0      
317GND              J7    -G2   D0200PA00X+136823Y+004095               S0      
317ENET10G_3_TDP    J7    -G1   D0200PA00X+137610Y+004134               S0      
317ENET1G_3_MDI1N   J7    -F2   D0200PA00X+136823Y+003543               S0      
317GND              J7    -F1   D0200PA00X+137610Y+003583               S0      
327NNAME10057       R25   -2          A01X+138429Y+009586X0180Y0200R180 S2      
327P3V3_BLAD2       R25   -1          A01X+138114Y+009586X0180Y0200R180 S2      
327ENET10G_3_LOS    R29   -2          A01X+138416Y+009156X0180Y0200R180 S2      
327P3V3_BLAD2       R29   -1          A01X+138101Y+009156X0180Y0200R180 S2      
327P3V3_BLAD2       R65   -2          A01X+136866Y+008684X0180Y0200R270 S2      
327NNAME10056       R65   -1          A01X+136866Y+008369X0180Y0200R270 S2      
327SFP3_PRESENT_N   R71   -2          A01X+137636Y+008331X0180Y0200R090 S2      
327GND              R71   -1          A01X+137636Y+008646X0180Y0200R090 S2      
327SFP3_PRESENT_N   R75   -2          A01X+138101Y+008304X0180Y0200     S2      
327NNAME10057       R75   -1          A01X+138416Y+008304X0180Y0200     S2      
327SFP3_PRESENT_N   R70   -2          A01X+138101Y+008724X0180Y0200     S2      
327ENET10G_3_LOS    R70   -1          A01X+138416Y+008724X0180Y0200     S2      
317GND              VIA   -     D0100PA00X+137160Y+008646               S3      
317ENET10G_3_LOS    VIA   -     D0100PA00X+138740Y+008724               S1      
317ENET10G_3_SCL    VIA   -     D0100PA00X+138990Y+009760               S1      
317P3V3_BLAD2       VIA   -     D0100PA00X+137160Y+009600               S3      
327SFP3_PRESENT_N   VIA   -           A01X+137636Y+007870X0300Y0300     S2      
327ENET10G_3_SDA    R21   -2          A01X+138429Y+010446X0180Y0200R180 S2      
327P3V3_BLAD2       R21   -1          A01X+138114Y+010446X0180Y0200R180 S2      
327ENET10G_3_SCL    R23   -2          A01X+138429Y+010016X0180Y0200R180 S2      
327P3V3_BLAD2       R23   -1          A01X+138114Y+010016X0180Y0200R180 S2      
317ENET1G_4_MDI3P   J23   -B7   D0350PA00X+136894Y+011567               S0      
317GND              J23   -G1   D0800PA00X+138992Y+011567               S0      
317ENET1G_4_MDI3N   J23   -B8   D0350PA00X+137394Y+012567               S0      
317GND              J23   -G2   D0800PA00X+138693Y+014067               S0      
317ENET1G_3_MDI0N   J23   -A2   D0350PA00X+136894Y+014165               S0      
317ENET1G_3_MDI0P   J23   -A1   D0350PA00X+137394Y+015165               S0      
317GND              J23   -G3   D0800PA00X+138992Y+019464               S0      
317N/C              J23   -H1   D1280UA00X+137894Y+017665               S0      
317GND              J17   -16   D0370PA00X+141215Y+003226               S0      
317GND              VIA   -     D0100PA00X+139568Y+002260               S3      
317GND              VIA   -     D0100PA00X+139098Y+002250               S3      
317GND              VIA   -     D0100PA00X+139088Y+001380               S3      
317GND              VIA   -     D0100PA00X+139568Y+001390               S3      
317ENET10G_3_RDN    VIA   -     D0100PA00X+139338Y+002058               S3      
317ENET10G_3_RDP    VIA   -     D0100PA00X+139338Y+001558               S3      
317N/C              U7    -21   D0630UA00X+141217Y+005665               S0      
317GND              J17   -19   D0370PA00X+140301Y+005038               S0      
317GND              J17   -10   D0410PA00X+140301Y+004053               S0      
317GND              J17   -18   D0370PA00X+140301Y+007006               S0      
317GND              J17   -9    D0410PA00X+140301Y+007990               S0      
317GND              J17   -17   D0370PA00X+140301Y+008856               S0      
317ENET10G_3_SDA    VIA   -     D0100PA00X+139520Y+009950               S1      
317NNAME10057       VIA   -     D0100PA00X+139100Y+009240               S1      
317GND              J17   -5    D0410PA00X+140301Y+011927               S0      
317GND              J17   -4    D0410PA00X+140301Y+015864               S0      
317GND              VIA   -     D0100PA00X+143370Y+000800               S3      
317GND              J17   -15   D0370PA00X+143104Y+003226               S0      
327GND              C29   -2          A01X+143340Y+001063X0180Y0200R090 S2      
327NNAME10058       C29   -1          A01X+143340Y+001378X0180Y0200R090 S2      
317NNAME10058       VIA   -     D0100PA00X+142953Y+001378               S3      
327GND              U7    -14         A01X+142713Y+004051X0200Y0800R180 S2      
327GND              U7    -11         A01X+141768Y+004051X0200Y0800R180 S2      
327NNAME10059       U7    -16         A01X+143343Y+004051X0200Y0800R180 S2      
327NNAME10058       U7    -15         A01X+143028Y+004051X0200Y0800R180 S2      
327ENET10G_3_RDN    U7    -12         A01X+142083Y+004051X0200Y0800R180 S2      
327ENET10G_3_RDP    U7    -13         A01X+142398Y+004051X0200Y0800R180 S2      
317GND              VIA   -     D0100PA00X+141768Y+004610               S3      
317GND              VIA   -     D0100PA00X+142713Y+004610               S3      
317GND              VIA   -     D0100PA00X+141768Y+003500               S3      
317GND              VIA   -     D0100PA00X+142700Y+003500               S3      
317NNAME10059       VIA   -     D0100PA00X+143343Y+004610               S3      
317NNAME10058       VIA   -     D0100PA00X+143028Y+004610               S3      
327GND              U7    -10         A01X+141610Y+007280X0200Y0800R180 S2      
327ENET10G_3_RS1    U7    -9          A01X+141925Y+007280X0200Y0800R180 S2      
327ENET10G_3_RS0    U7    -7          A01X+142555Y+007280X0200Y0800R180 S2      
327ENET10G_3_SDA    U7    -4          A01X+143500Y+007280X0200Y0800R180 S2      
327ENET10G_3_SCL    U7    -5          A01X+143185Y+007280X0200Y0800R180 S2      
327NNAME10057       U7    -6          A01X+142870Y+007280X0200Y0800R180 S2      
327ENET10G_3_LOS    U7    -8          A01X+142240Y+007280X0200Y0800R180 S2      
317GND              J17   -8    D0410PA00X+141549Y+009959               S0      
317GND              J17   -7    D0410PA00X+143675Y+009959               S0      
317GND              VIA   -     D0100PA00X+141610Y+007840               S3      
317ENET10G_3_LOS    VIA   -     D0100PA00X+142240Y+007840               S3      
317ENET10G_3_RS0    VIA   -     D0100PA00X+143420Y+008810               S3      
317ENET10G_3_SDA    VIA   -     D0100PA00X+143500Y+008170               S3      
317ENET10G_3_SCL    VIA   -     D0100PA00X+143185Y+008020               S3      
317NNAME10057       VIA   -     D0100PA00X+142870Y+007900               S3      
317ENET10G_3_RS1    VIA   -     D0100PA00X+142940Y+008850               S3      
317GND              J17   -2    D0410PA00X+142533Y+017833               S0      
317GND              VIA   -     D0100PA00X+144240Y+000820               S1      
317GND              VIA   -     D0100PA00X+143800Y+000810               S3      
317GND              J17   -14   D0370PA00X+144994Y+003226               S0      
327GND              C26   -2          A01X+144700Y+001073X0180Y0200R090 S2      
327NNAME10059       C26   -1          A01X+144700Y+001388X0180Y0200R090 S2      
327GND              C30   -2          A01X+143790Y+001063X0180Y0200R090 S2      
327NNAME10058       C30   -1          A01X+143790Y+001378X0180Y0200R090 S2      
327GND              C25   -2          A01X+144260Y+001073X0180Y0200R090 S2      
327NNAME10059       C25   -1          A01X+144260Y+001388X0180Y0200R090 S2      
317GND              VIA   -     D0100PA00X+144630Y+000830               S3      
317GND              VIA   -     D0100PA00X+143650Y+002390               S3      
317GND              VIA   -     D0100PA00X+143650Y+002070               S3      
317GND              VIA   -     D0100PA00X+144590Y+002080               S3      
317GND              VIA   -     D0100PA00X+144570Y+002440               S3      
317ENET10G_3_TDN    VIA   -     D0100PA00X+144380Y+002250               S3      
317ENET10G_3_TDP    VIA   -     D0100PA00X+143880Y+002250               S3      
317NNAME10059       VIA   -     D0100PA00X+145460Y+001760               S3      
327GND              U7    -20         A01X+144603Y+004051X0200Y0800R180 S2      
327GND              U7    -17         A01X+143658Y+004051X0200Y0800R180 S2      
327ENET10G_3_TDN    U7    -19         A01X+144288Y+004051X0200Y0800R180 S2      
327ENET10G_3_TDP    U7    -18         A01X+143973Y+004051X0200Y0800R180 S2      
317N/C              U7    -22   D0380UA00X+144996Y+005665               S0      
317GND              J17   -13   D0370PA00X+145911Y+005038               S0      
317GND              VIA   -     D0100PA00X+144603Y+004610               S3      
317GND              VIA   -     D0100PA00X+143658Y+004610               S3      
317GND              VIA   -     D0100PA00X+144590Y+003500               S3      
317GND              VIA   -     D0100PA00X+143658Y+003500               S3      
327GND              U7    -1          A01X+144445Y+007280X0200Y0800R180 S2      
327NNAME10060       U7    -2          A01X+144130Y+007280X0200Y0800R180 S2      
327NNAME10061       U7    -3          A01X+143815Y+007280X0200Y0800R180 S2      
317GND              J17   -20   D0330PA00X+145911Y+006022               S0      
317GND              J17   -12   D0370PA00X+145911Y+007006               S0      
317GND              J17   -6    D0410PA00X+145911Y+009959               S0      
317GND              J17   -11   D0370PA00X+145911Y+008856               S0      
317GND              VIA   -     D0100PA00X+144445Y+007830               S3      
317NNAME10060       VIA   -     D0100PA00X+144130Y+007910               S3      
317NNAME10061       VIA   -     D0100PA00X+143815Y+008110               S3      
317GND              J17   -3    D0410PA00X+145911Y+013896               S0      
317GND              J17   -1    D0410PA00X+145911Y+017833               S0      
317GND              J6    -2    D1580PA00X+148213Y+001969               S0      
317GND              J6    -1    D1580PA00X+148213Y+004185               S0      
317GND              J6    -3    D1580PA00X+148213Y+006791               S0      
327NNAME10060       R17   -2          A01X+148122Y+009306X0180Y0200R180 S2      
327P3V3_BLAD2       R17   -1          A01X+147807Y+009306X0180Y0200R180 S2      
327NNAME10061       R19   -2          A01X+148122Y+009806X0180Y0200R180 S2      
327P3V3_BLAD2       R19   -1          A01X+147807Y+009806X0180Y0200R180 S2      
327ENET10G_3_RS0    R27   -2          A01X+148122Y+010326X0180Y0200R180 S2      
327P3V3_BLAD2       R27   -1          A01X+147807Y+010326X0180Y0200R180 S2      
327ENET10G_3_RS1    R31   -2          A01X+148122Y+010936X0180Y0200R180 S2      
327P3V3_BLAD2       R31   -1          A01X+147807Y+010936X0180Y0200R180 S2      
327P3V3_BLAD2       R80   -1          A01X+148076Y+011756X0440Y0540R180 S2      
317P3V3_BLAD2       VIA   -     D0100PA00X+147240Y+010270               S3      
317P3V3_BLAD2       VIA   -     D0100PA00X+147420Y+010660               S3      
327P3V3_BLAD2       R81   -1          A01X+148076Y+012636X0440Y0540R180 S2      
327P3V3_BLAD2       FS5   -1          A01X+148071Y+016229X0400Y0710     S2      
327P3V3_BLAD2       FS7   -1          A01X+148079Y+015260X0400Y0710     S2      
327NNAME10060       R50   -2          A01X+148831Y+009306X0180Y0200     S2      
327GND              R50   -1          A01X+149146Y+009306X0180Y0200     S2      
327NNAME10061       R51   -2          A01X+148831Y+009806X0180Y0200     S2      
327GND              R51   -1          A01X+149146Y+009806X0180Y0200     S2      
317GND              VIA   -     D0100PA00X+149420Y+009780               S1      
317GND              VIA   -     D0100PA00X+149500Y+009280               S1      
317NNAME10060       VIA   -     D0100PA00X+148470Y+009306               S1      
317NNAME10061       VIA   -     D0100PA00X+148500Y+009806               S1      
327ENET10G_3_RS0    R48   -2          A01X+148831Y+010326X0180Y0200     S2      
327GND              R48   -1          A01X+149146Y+010326X0180Y0200     S2      
327ENET10G_3_RS1    R49   -2          A01X+148831Y+010936X0180Y0200     S2      
327GND              R49   -1          A01X+149146Y+010936X0180Y0200     S2      
317GND              U9    -G3   D0990PA00X+150936Y+010862               S0      
327NNAME10059       R80   -2          A01X+148824Y+011756X0440Y0540R180 S2      
317GND              VIA   -     D0100PA00X+149470Y+011120               S3      
317GND              VIA   -     D0100PA00X+149450Y+010270               S3      
317ENET10G_3_RS0    VIA   -     D0100PA00X+148490Y+010326               S1      
317NNAME10059       VIA   -     D0100PA00X+149230Y+011756               S1      
317ENET10G_3_RS1    VIA   -     D0100PA00X+148480Y+010936               S1      
327NNAME10059       L5    -2          A01X+149580Y+013576X0440Y0540R090 S2      
327NNAME10062       L5    -1          A01X+149580Y+014324X0440Y0540R090 S2      
327NNAME10058       L7    -2          A01X+148760Y+013576X0440Y0540R090 S2      
327NNAME10063       L7    -1          A01X+148760Y+014324X0440Y0540R090 S2      
327NNAME10058       R81   -2          A01X+148824Y+012636X0440Y0540R180 S2      
317NNAME10058       VIA   -     D0100PA00X+149204Y+012636               S1      
327NNAME10062       FS5   -2          A01X+149213Y+016229X0400Y0710     S2      
327NNAME10063       FS7   -2          A01X+149221Y+015260X0400Y0710     S2      
317GND              U9    -G1   D0990PA00X+150936Y+016768               S0      
317NNAME10062       VIA   -     D0100PA00X+149580Y+014780               S1      
317NNAME10063       VIA   -     D0100PA00X+148760Y+014700               S1      
317GND              J8    -A6   D0200PA00X+151925Y+000787               S0      
317NNAME10064       J8    -A5   D0200PA00X+152713Y+000827               S0      
317GND              VIA   -     D0100PA00X+152720Y+000380               S3      
317NNAME10065       J8    -E6   D0200PA00X+151925Y+002992               S0      
317NNAME10066       J8    -E5   D0200PA00X+152713Y+003032               S0      
317GND              J8    -D6   D0200PA00X+151925Y+002441               S0      
317NNAME10067       J8    -D5   D0200PA00X+152713Y+002480               S0      
317NNAME10068       J8    -C6   D0200PA00X+151925Y+001890               S0      
317GND              J8    -C5   D0200PA00X+152713Y+001929               S0      
317NNAME10069       J8    -B6   D0200PA00X+151925Y+001339               S0      
317NNAME10070       J8    -B5   D0200PA00X+152713Y+001378               S0      
317NNAME10071       J8    -I6   D0200PA00X+151925Y+005197               S0      
317GND              J8    -I5   D0200PA00X+152713Y+005236               S0      
317NNAME10072       J8    -H6   D0200PA00X+151925Y+004646               S0      
317NNAME10073       J8    -H5   D0200PA00X+152713Y+004685               S0      
317GND              J8    -G6   D0200PA00X+151925Y+004095               S0      
317NNAME10074       J8    -G5   D0200PA00X+152713Y+004134               S0      
317NNAME10075       J8    -F6   D0200PA00X+151925Y+003543               S0      
317GND              J8    -F5   D0200PA00X+152713Y+003583               S0      
317GND              VIA   -     D0100PA00X+151820Y+005560               S3      
317NNAME10075       VIA   -     D0100PA00X+152448Y+009710               S1      
317NNAME10065       VIA   -     D0100PA00X+152448Y+009210               S1      
317GND              VIA   -     D0100PA00X+152158Y+009470               S3      
317GND              VIA   -     D0100PA00X+152118Y+009110               S3      
317N/C              U4    -H1   D0630UA00X+152553Y+013224               S0      
317GND              U9    -G2   D0620PA00X+151129Y+013224               S0      
317GND              J8    -A4   D0200PA00X+153500Y+000787               S0      
317AIRMAX_RSVD7     J8    -A3   D0200PA00X+154287Y+000827               S0      
317GND              J8    -A2   D0200PA00X+155075Y+000787               S0      
317NNAME10076       J8    -E4   D0200PA00X+153500Y+002992               S0      
317NNAME10077       J8    -E3   D0200PA00X+154287Y+003032               S0      
317NNAME10078       J8    -E2   D0200PA00X+155075Y+002992               S0      
317GND              J8    -D4   D0200PA00X+153500Y+002441               S0      
317NNAME10079       J8    -D3   D0200PA00X+154287Y+002480               S0      
317GND              J8    -D2   D0200PA00X+155075Y+002441               S0      
317AIRMAX_RSVD6     J8    -C4   D0200PA00X+153500Y+001890               S0      
317GND              J8    -C3   D0200PA00X+154287Y+001929               S0      
317NNAME10080       J8    -C2   D0200PA00X+155075Y+001890               S0      
317AIRMAX_RSVD5     J8    -B4   D0200PA00X+153500Y+001339               S0      
317AIRMAX_RSVD8     J8    -B3   D0200PA00X+154287Y+001378               S0      
317NNAME10081       J8    -B2   D0200PA00X+155075Y+001339               S0      
317NNAME10082       J8    -I4   D0200PA00X+153500Y+005197               S0      
317GND              J8    -I3   D0200PA00X+154287Y+005236               S0      
317NNAME10083       J8    -I2   D0200PA00X+155075Y+005197               S0      
317NNAME10084       J8    -H4   D0200PA00X+153500Y+004646               S0      
317NNAME10085       J8    -H3   D0200PA00X+154287Y+004685               S0      
317NNAME10086       J8    -H2   D0200PA00X+155075Y+004646               S0      
317GND              J8    -G4   D0200PA00X+153500Y+004095               S0      
317NNAME10087       J8    -G3   D0200PA00X+154287Y+004134               S0      
317GND              J8    -G2   D0200PA00X+155075Y+004095               S0      
317NNAME10088       J8    -F4   D0200PA00X+153500Y+003543               S0      
317GND              J8    -F3   D0200PA00X+154287Y+003583               S0      
317NNAME10089       J8    -F2   D0200PA00X+155075Y+003543               S0      
317NNAME10070       VIA   -     D0100PA00X+153439Y+007290               S1      
317NNAME10064       VIA   -     D0100PA00X+152939Y+007290               S1      
317GND              VIA   -     D0100PA00X+155050Y+007550               S1      
317GND              VIA   -     D0100PA00X+153728Y+007570               S3      
317GND              VIA   -     D0100PA00X+153168Y+007590               S3      
317GND              VIA   -     D0100PA00X+153530Y+005580               S3      
327GND              U4    -B13        A01X+153104Y+010197X0150Y0730R180 S2      
327NNAME10075       U4    -B12        A01X+153419Y+010197X0150Y0730R180 S2      
327NNAME10065       U4    -B11        A01X+153734Y+010197X0150Y0730R180 S2      
327GND              U4    -B10        A01X+154049Y+010197X0150Y0730R180 S2      
327NNAME10073       U4    -B9         A01X+154364Y+010197X0150Y0730R180 S2      
327NNAME10074       U4    -B8         A01X+154679Y+010197X0150Y0730R180 S2      
327GND              U4    -B7         A01X+154994Y+010197X0150Y0730R180 S2      
327GND              U9    -B3         A01X+154050Y+008254X0360Y0840     S2      
327GND              U9    -B2         A01X+154995Y+008254X0360Y0840     S2      
317NNAME10073       VIA   -     D0100PA00X+154272Y+009329               S1      
317NNAME10074       VIA   -     D0100PA00X+154772Y+009329               S1      
317GND              VIA   -     D0100PA00X+154994Y+009654               S3      
317GND              VIA   -     D0100PA00X+154049Y+009649               S3      
327GND              U4    -A13        A01X+152947Y+011185X0150Y0730R180 S2      
327NNAME10068       U4    -A12        A01X+153262Y+011185X0150Y0730R180 S2      
327NNAME10069       U4    -A11        A01X+153577Y+011185X0150Y0730R180 S2      
327GND              U4    -A10        A01X+153892Y+011185X0150Y0730R180 S2      
327NNAME10071       U4    -A9         A01X+154207Y+011185X0150Y0730R180 S2      
327NNAME10072       U4    -A8         A01X+154522Y+011185X0150Y0730R180 S2      
327GND              U4    -A7         A01X+154837Y+011185X0150Y0730R180 S2      
317NNAME10068       VIA   -     D0100PA00X+153169Y+012100               S1      
317GND              VIA   -     D0100PA00X+152848Y+010250               S3      
317GND              VIA   -     D0100PA00X+154837Y+012270               S3      
317GND              VIA   -     D0100PA00X+153892Y+011766               S3      
317GND              VIA   -     D0100PA00X+152947Y+011749               S3      
317NNAME10069       VIA   -     D0100PA00X+153669Y+012100               S1      
317NNAME10072       VIA   -     D0100PA00X+154614Y+012593               S1      
317NNAME10066       VIA   -     D0100PA00X+155069Y+012960               S1      
317GND              VIA   -     D0100PA00X+155098Y+013320               S3      
317GND              VIA   -     D0100PA00X+153758Y+012620               S3      
317NNAME10071       VIA   -     D0100PA00X+154114Y+012593               S1      
317NNAME10090       J8    -A1   D0200PA00X+155862Y+000827               S0      
317GND              VIA   -     D0100PA00X+155900Y+000420               S3      
317NNAME10091       J8    -E1   D0200PA00X+155862Y+003032               S0      
317NNAME10092       J8    -D1   D0200PA00X+155862Y+002480               S0      
317GND              J8    -C1   D0200PA00X+155862Y+001929               S0      
317NNAME10093       J8    -B1   D0200PA00X+155862Y+001378               S0      
317AIRMAX_RSVD6     VIA   -     D0100PA00X+157080Y+001890               S1      
317GND              J8    -I1   D0200PA00X+155862Y+005236               S0      
317NNAME10094       J8    -H1   D0200PA00X+155862Y+004685               S0      
317NNAME10095       J8    -G1   D0200PA00X+155862Y+004134               S0      
317GND              J8    -F1   D0200PA00X+155862Y+003583               S0      
327AIRMAX_RSVD7     VIA   -           A01X+157230Y+005350X0300Y0300     S2      
317GND              VIA   -     D0100PA00X+155180Y+005570               S3      
327NNAME10070       U4    -B6         A01X+155309Y+010197X0150Y0730R180 S2      
327NNAME10064       U4    -B5         A01X+155624Y+010197X0150Y0730R180 S2      
327GND              U4    -B4         A01X+155939Y+010197X0150Y0730R180 S2      
327NNAME10088       U4    -B3         A01X+156254Y+010197X0150Y0730R180 S2      
327NNAME10076       U4    -B2         A01X+156569Y+010197X0150Y0730R180 S2      
327GND              U4    -B1         A01X+156884Y+010197X0150Y0730R180 S2      
327GND              U9    -B1         A01X+155940Y+008254X0360Y0840     S2      
317NNAME10088       VIA   -     D0100PA00X+157175Y+009210               S1      
317NNAME10076       VIA   -     D0100PA00X+157175Y+009710               S1      
317GND              VIA   -     D0100PA00X+155980Y+008940               S1      
317GND              VIA   -     D0100PA00X+155939Y+009631               S1      
317GND              VIA   -     D0100PA00X+156848Y+009030               S3      
327NNAME10066       U4    -A6         A01X+155152Y+011185X0150Y0730R180 S2      
327NNAME10067       U4    -A5         A01X+155467Y+011185X0150Y0730R180 S2      
327GND              U4    -A4         A01X+155781Y+011185X0150Y0730R180 S2      
327NNAME10082       U4    -A3         A01X+156096Y+011185X0150Y0730R180 S2      
327NNAME10084       U4    -A2         A01X+156411Y+011185X0150Y0730R180 S2      
327GND              U4    -A1         A01X+156726Y+011185X0150Y0730R180 S2      
317GND              VIA   -     D0100PA00X+157181Y+010197               S3      
317GND              VIA   -     D0100PA00X+155781Y+011870               S3      
317GND              VIA   -     D0100PA00X+156726Y+011739               S3      
317NNAME10084       VIA   -     D0100PA00X+156504Y+012203               S1      
317NNAME10082       VIA   -     D0100PA00X+156004Y+012203               S1      
317N/C              U4    -H2   D0630UA00X+157278Y+013224               S0      
317NNAME10067       VIA   -     D0100PA00X+155569Y+012960               S1      
317GND              VIA   -     D0100PA00X+155568Y+013320               S3      
327AIRMAX_RSVD8     VIA   -           A01X+157930Y+005790X0300Y0300     S2      
327AIRMAX_RSVD5     VIA   -           A01X+158610Y+006050X0300Y0300     S2      
317NNAME10087       VIA   -     D0100PA00X+159448Y+010560               S1      
317GND              VIA   -     D0100PA00X+159290Y+010170               S3      
317GND              VIA   -     D0100PA00X+159330Y+011900               S3      
317NNAME10079       VIA   -     D0100PA00X+159539Y+011539               S1      
317N/C              U2    -H1   D0630UA00X+160037Y+013224               S0      
327GND              U2    -B13        A01X+160589Y+010197X0150Y0730R180 S2      
327NNAME10085       U2    -B12        A01X+160904Y+010197X0150Y0730R180 S2      
327NNAME10087       U2    -B11        A01X+161219Y+010197X0150Y0730R180 S2      
327GND              U2    -B10        A01X+161534Y+010197X0150Y0730R180 S2      
327NNAME10089       U2    -B9         A01X+161848Y+010197X0150Y0730R180 S2      
327GND              U9    -A3         A01X+161535Y+008254X0360Y0840     S2      
317NNAME10089       VIA   -     D0100PA00X+161756Y+009283               S1      
317GND              VIA   -     D0100PA00X+161038Y+008730               S1      
317GND              VIA   -     D0100PA00X+160589Y+009659               S1      
317GND              VIA   -     D0100PA00X+161533Y+009604               S3      
327GND              U2    -A13        A01X+160431Y+011185X0150Y0730R180 S2      
327NNAME10077       U2    -A12        A01X+160746Y+011185X0150Y0730R180 S2      
327NNAME10079       U2    -A11        A01X+161061Y+011185X0150Y0730R180 S2      
327GND              U2    -A10        A01X+161376Y+011185X0150Y0730R180 S2      
327NNAME10080       U2    -A9         A01X+161691Y+011185X0150Y0730R180 S2      
317NNAME10085       VIA   -     D0100PA00X+159948Y+010560               S1      
317NNAME10077       VIA   -     D0100PA00X+160039Y+011539               S1      
317GND              VIA   -     D0100PA00X+161376Y+011740               S3      
317GND              VIA   -     D0100PA00X+160203Y+011185               S3      
317GND              VIA   -     D0100PA00X+160090Y+010870               S3      
317NNAME10080       VIA   -     D0100PA00X+161598Y+012045               S1      
327N/C                    -           A01X+163640Y+004320X0400Y0400     S2      
327N/C                    -           A08X+163640Y+004310X0400Y0400     S1      
317GND              VIA   -     D0100PA00X+163568Y+007480               S3      
317GND              VIA   -     D0100PA00X+162318Y+007510               S3      
317NNAME10094       VIA   -     D0100PA00X+162701Y+007290               S1      
317NNAME10095       VIA   -     D0100PA00X+163201Y+007290               S1      
327NNAME10078       U2    -B8         A01X+162163Y+010197X0150Y0730R180 S2      
327GND              U2    -B7         A01X+162478Y+010197X0150Y0730R180 S2      
327NNAME10094       U2    -B6         A01X+162793Y+010197X0150Y0730R180 S2      
327NNAME10095       U2    -B5         A01X+163108Y+010197X0150Y0730R180 S2      
327GND              U2    -B4         A01X+163423Y+010197X0150Y0730R180 S2      
327NNAME10093       U2    -B3         A01X+163738Y+010197X0150Y0730R180 S2      
327NNAME10090       U2    -B2         A01X+164053Y+010197X0150Y0730R180 S2      
327GND              U9    -A2         A01X+162480Y+008254X0360Y0840     S2      
327GND              U9    -A1         A01X+163424Y+008254X0360Y0840     S2      
317NNAME10078       VIA   -     D0100PA00X+162256Y+009283               S1      
317GND              VIA   -     D0100PA00X+162478Y+009620               S3      
317GND              VIA   -     D0100PA00X+163423Y+009615               S1      
327NNAME10081       U2    -A8         A01X+162006Y+011185X0150Y0730R180 S2      
327GND              U2    -A7         A01X+162321Y+011185X0150Y0730R180 S2      
327NNAME10083       U2    -A6         A01X+162636Y+011185X0150Y0730R180 S2      
327NNAME10086       U2    -A5         A01X+162951Y+011185X0150Y0730R180 S2      
327GND              U2    -A4         A01X+163266Y+011185X0150Y0730R180 S2      
327NNAME10091       U2    -A3         A01X+163581Y+011185X0150Y0730R180 S2      
327NNAME10092       U2    -A2         A01X+163896Y+011185X0150Y0730R180 S2      
327GND              U2    -A1         A01X+164211Y+011185X0150Y0730R180 S2      
317NNAME10081       VIA   -     D0100PA00X+162098Y+012045               S1      
317NNAME10092       VIA   -     D0100PA00X+163988Y+012033               S1      
317GND              VIA   -     D0100PA00X+162321Y+011730               S3      
317GND              VIA   -     D0100PA00X+164211Y+011730               S3      
317GND              VIA   -     D0100PA00X+163266Y+011730               S3      
317GND              VIA   -     D0100PA00X+162430Y+012150               S3      
317NNAME10091       VIA   -     D0100PA00X+163488Y+012033               S1      
317NNAME10083       VIA   -     D0100PA00X+162549Y+012473               S1      
317NNAME10086       VIA   -     D0100PA00X+163049Y+012473               S1      
317GND              VIA   -     D0100PA00X+163418Y+012430               S3      
317N/C              H8    -1    D1420UA00X+167051Y+001850               S0      
317GND              H8    -9    D0220PA00X+166102Y+002800               S0      
317GND              H8    -3    D0220PA00X+166102Y+000901               S0      
317GND              H8    -2    D0220PA00X+165708Y+001850               S0      
327GND              U2    -B1         A01X+164368Y+010197X0150Y0730R180 S2      
317NNAME10090       VIA   -     D0100PA00X+164828Y+009713               S1      
317GND              VIA   -     D0100PA00X+164468Y+009030               S3      
317NNAME10093       VIA   -     D0100PA00X+164828Y+009213               S1      
317GND              U9    -G6   D0990PA00X+166377Y+010862               S0      
317GND              VIA   -     D0100PA00X+164611Y+010197               S1      
317N/C              U2    -H2   D0630UA00X+164762Y+013224               S0      
317GND              U9    -G5   D0620PA00X+166184Y+013224               S0      
317GND              U9    -G4   D0990PA00X+166377Y+016768               S0      
317GND              H8    -4    D0220PA00X+167051Y+000507               S0      
317GND              H8    -7    D0220PA00X+168001Y+002800               S0      
317GND              H8    -6    D0220PA00X+168394Y+001850               S0      
317GND              H8    -5    D0220PA00X+168001Y+000901               S0      
317GND              H8    -8    D0220PA00X+167051Y+003193               S0      
327GND              NDPAD2-1          A08X+167642Y+010276X1030Y4260     S1      
317GND              VIA   -     D0100PA00X+167610Y+007890               S3      
327GND              NDPAD1-1          A01X+167642Y+011457X1030Y1890     S2      
P  NNAME10000 P3V3_10G_2_VCCT
P  NNAME10001 P3V3_10G_2_VCCT_L
P  NNAME10002 P3V3_10G_2_VCCR_L
P  NNAME10003 P3V3_10G_2_VCCR
P  NNAME10004 ENET10G_2_TX_DIS
P  NNAME10005 ENET10G_2_TX_FAULT
P  NNAME10006 ENET10G_2_MOD_DEF0
P  NNAME10007 SKU_PIN_BLAD1_2
P  NNAME10008 SKU_PIN_BLAD1_1
P  NNAME10009 ENET10G_1_MOD_DEF0
P  NNAME10010 P3V3_10G_1_VCCR
P  NNAME10011 P3V3_10G_1_VCCT
P  NNAME10012 ENET10G_1_TX_FAULT
P  NNAME10013 ENET10G_1_TX_DIS
P  NNAME10014 P3V3_10G_1_VCCR_L
P  NNAME10015 P3V3_10G_1_VCCT_L
P  NNAME10016 SAS_BLAD1_TX8_P
P  NNAME10017 SAS_BLAD1_RX8_N
P  NNAME10018 SAS_BLAD1_RX8_P
P  NNAME10019 SAS_BLAD1_RX7_N
P  NNAME10020 SAS_BLAD1_RX7_P
P  NNAME10021 SAS_BLAD1_TX8_N
P  NNAME10022 SAS_BLAD1_TX6_P
P  NNAME10023 SAS_BLAD1_RX6_N
P  NNAME10024 SAS_BLAD1_TX5_P
P  NNAME10025 SAS_BLAD1_RX4_N
P  NNAME10026 SAS_BLAD1_RX6_P
P  NNAME10027 SAS_BLAD1_RX4_P
P  NNAME10028 SAS_BLAD1_TX6_N
P  NNAME10029 SAS_BLAD1_RX5_N
P  NNAME10030 SAS_BLAD1_TX7_N
P  NNAME10031 SAS_BLAD1_RX5_P
P  NNAME10032 SAS_BLAD1_TX4_N
P  NNAME10033 SAS_BLAD1_TX7_P
P  NNAME10034 SAS_BLAD1_TX4_P
P  NNAME10035 SAS_BLAD1_TX5_N
P  NNAME10036 SAS_BLAD1_TX1_P
P  NNAME10037 SAS_BLAD1_TX3_P
P  NNAME10038 SAS_BLAD1_RX1_N
P  NNAME10039 SAS_BLAD1_RX1_P
P  NNAME10040 SAS_BLAD1_RX3_N
P  NNAME10041 SAS_BLAD1_RX3_P
P  NNAME10042 SAS_BLAD1_TX1_N
P  NNAME10043 SAS_BLAD1_RX2_N
P  NNAME10044 SAS_BLAD1_RX2_P
P  NNAME10045 SAS_BLAD1_TX2_N
P  NNAME10046 SAS_BLAD1_TX2_P
P  NNAME10047 SAS_BLAD1_TX3_N
P  NNAME10048 P3V3_10G_4_VCCR
P  NNAME10049 P3V3_10G_4_VCCR_L
P  NNAME10050 ENET10G_4_TX_FAULT
P  NNAME10051 ENET10G_4_TX_DIS
P  NNAME10052 P3V3_10G_4_VCCT_L
P  NNAME10053 P3V3_10G_4_VCCT
P  NNAME10054 ENET10G_4_MOD_DEF0
P  NNAME10055 SKU_PIN_BLAD2_2
P  NNAME10056 SKU_PIN_BLAD2_1
P  NNAME10057 ENET10G_3_MOD_DEF0
P  NNAME10058 P3V3_10G_3_VCCR
P  NNAME10059 P3V3_10G_3_VCCT
P  NNAME10060 ENET10G_3_TX_FAULT
P  NNAME10061 ENET10G_3_TX_DIS
P  NNAME10062 P3V3_10G_3_VCCT_L
P  NNAME10063 P3V3_10G_3_VCCR_L
P  NNAME10064 SAS_BLAD2_TX6_P
P  NNAME10065 SAS_BLAD2_TX8_P
P  NNAME10066 SAS_BLAD2_RX6_N
P  NNAME10067 SAS_BLAD2_RX6_P
P  NNAME10068 SAS_BLAD2_RX8_N
P  NNAME10069 SAS_BLAD2_RX8_P
P  NNAME10070 SAS_BLAD2_TX6_N
P  NNAME10071 SAS_BLAD2_RX7_N
P  NNAME10072 SAS_BLAD2_RX7_P
P  NNAME10073 SAS_BLAD2_TX7_N
P  NNAME10074 SAS_BLAD2_TX7_P
P  NNAME10075 SAS_BLAD2_TX8_N
P  NNAME10076 SAS_BLAD2_TX5_P
P  NNAME10077 SAS_BLAD2_RX4_N
P  NNAME10078 SAS_BLAD2_TX3_P
P  NNAME10079 SAS_BLAD2_RX4_P
P  NNAME10080 SAS_BLAD2_RX3_N
P  NNAME10081 SAS_BLAD2_RX3_P
P  NNAME10082 SAS_BLAD2_RX5_N
P  NNAME10083 SAS_BLAD2_RX2_N
P  NNAME10084 SAS_BLAD2_RX5_P
P  NNAME10085 SAS_BLAD2_TX4_N
P  NNAME10086 SAS_BLAD2_RX2_P
P  NNAME10087 SAS_BLAD2_TX4_P
P  NNAME10088 SAS_BLAD2_TX5_N
P  NNAME10089 SAS_BLAD2_TX3_N
P  NNAME10090 SAS_BLAD2_TX1_P
P  NNAME10091 SAS_BLAD2_RX1_N
P  NNAME10092 SAS_BLAD2_RX1_P
P  NNAME10093 SAS_BLAD2_TX1_N
P  NNAME10094 SAS_BLAD2_TX2_N
P  NNAME10095 SAS_BLAD2_TX2_P
999
